G04 ================== begin FILE IDENTIFICATION RECORD ==================*
G04 Layout Name:  D:/<user>/Wistron_project/16369-1_ECN/16369-1.brd*
G04 Film Name:    BSILK*
G04 File Format:  Gerber RS274X*
G04 File Origin:  Cadence Allegro 16.5-S056*
G04 Origin Date:  Mon Jun 12 14:38:55 2017*
G04 *
G04 Layer:  VIA CLASS/FILMMASKBOTTOM*
G04 Layer:  REF DES/ASSEMBLY_BOTTOM*
G04 Layer:  PACKAGE GEOMETRY/SILKSCREEN_BOTTOM*
G04 Layer:  DRAWING FORMAT/LAYER_PCB_STORY*
G04 Layer:  DRAWING FORMAT/LAYER_SILK_B*
G04 Layer:  BOARD GEOMETRY/SILKSCREEN_BOTTOM*
G04 *
G04 Offset:    (0.00 0.00)*
G04 Mirror:    No*
G04 Mode:      Positive*
G04 Rotation:  0*
G04 FullContactRelief:  No*
G04 UndefLineWidth:     6.00*
G04 ================== end FILE IDENTIFICATION RECORD ====================*
%FSLAX35Y35*MOIN*%
%IR0*IPPOS*OFA0.00000B0.00000*MIA0B0*SFA1.00000B1.00000*%
%ADD10C,.02*%
%ADD11C,.015*%
%ADD12C,.018*%
%ADD13C,.002*%
%ADD14C,.006*%
G75*
%LPD*%
G75*
G36*
G01X68900Y79421D02*
X68657Y79239D01*
X68475Y79178D01*
X68231Y78995D01*
X68049Y78934D01*
X67806Y78752D01*
X67623Y78691D01*
X67380Y78509D01*
X67076Y78387D01*
X66833Y78204D01*
X66650Y78144D01*
X66407Y77961D01*
X66224Y77900D01*
X65981Y77718D01*
X65798Y77657D01*
X65555Y77475D01*
X65251Y77353D01*
X65008Y77170D01*
X64826Y77110D01*
X64582Y76927D01*
X64400Y76867D01*
X64156Y76684D01*
X63974Y76623D01*
X63731Y76441D01*
X63548Y76380D01*
X63305Y76198D01*
X63001Y76076D01*
X62757Y75893D01*
X62575Y75833D01*
X62332Y75650D01*
X62150Y75589D01*
X61906Y75407D01*
X61845D01*
X61724Y75285D01*
X61785Y75224D01*
X62757Y75163D01*
X62819Y75103D01*
X63974Y75042D01*
X64035Y74981D01*
X65251Y74920D01*
X65312Y74859D01*
X66468Y74799D01*
X66528Y74738D01*
X67745Y74677D01*
X67806Y74616D01*
X68961Y74556D01*
X69022Y74494D01*
X69144D01*
Y69629D01*
X69083Y69690D01*
X68475Y69751D01*
X68414Y69811D01*
X67806Y69872D01*
X67745Y69933D01*
X67197Y69994D01*
X67137Y70055D01*
X66528Y70116D01*
X66468Y70176D01*
X65859Y70237D01*
X65798Y70298D01*
X65251Y70359D01*
X65191Y70420D01*
X64582Y70480D01*
X64521Y70541D01*
X63913Y70602D01*
X63852Y70663D01*
X63305Y70724D01*
X63244Y70785D01*
X62636Y70845D01*
X62575Y70906D01*
X61967Y70967D01*
X61906Y71028D01*
X61359Y71089D01*
X61298Y71150D01*
X60690Y71210D01*
X60629Y71271D01*
X60021Y71332D01*
X59960Y71393D01*
X59413Y71454D01*
X59352Y71515D01*
X58744Y71575D01*
X58683Y71636D01*
X58074Y71697D01*
X58014Y71757D01*
X57467Y71819D01*
X57406Y71879D01*
X56797Y71940D01*
X56737Y72001D01*
X56128Y72062D01*
X56067Y72122D01*
X55824Y72001D01*
X55581Y71819D01*
X55277Y71697D01*
X55033Y71515D01*
X54851Y71454D01*
X54608Y71271D01*
X54426Y71210D01*
X54182Y71028D01*
X54000Y70967D01*
X53756Y70785D01*
X53452Y70663D01*
X53209Y70480D01*
X53026Y70420D01*
X52783Y70237D01*
X52601Y70176D01*
X52357Y69994D01*
X52175Y69933D01*
X51932Y69751D01*
X51628Y69629D01*
X51384Y69446D01*
X51202Y69386D01*
X50959Y69203D01*
X50776Y69143D01*
X50533Y68960D01*
X50350Y68899D01*
X50107Y68717D01*
X49803Y68595D01*
X49681Y68474D01*
Y73582D01*
X49864Y73643D01*
X50107Y73826D01*
X50290Y73886D01*
X50533Y74069D01*
X50715Y74130D01*
X50959Y74312D01*
X51263Y74434D01*
X51506Y74616D01*
X51689Y74677D01*
X51932Y74859D01*
X52114Y74920D01*
X52357Y75103D01*
X52540Y75163D01*
X52783Y75346D01*
X53087Y75468D01*
X53331Y75650D01*
X53513Y75711D01*
X53756Y75893D01*
X53939Y75954D01*
X54182Y76137D01*
X54365Y76198D01*
X54608Y76380D01*
X54790Y76441D01*
X55033Y76623D01*
X55338Y76745D01*
X55581Y76927D01*
X55763Y76988D01*
X56007Y77170D01*
X56189Y77231D01*
X56432Y77414D01*
X56615Y77475D01*
X56858Y77657D01*
X57162Y77779D01*
X57406Y77961D01*
X57588Y78022D01*
X57831Y78204D01*
X58014Y78265D01*
X58257Y78448D01*
X58439Y78509D01*
X58683Y78691D01*
X58987Y78813D01*
X59230Y78995D01*
X59413Y79056D01*
X59656Y79239D01*
X59838Y79299D01*
X60081Y79482D01*
X60264Y79543D01*
X60507Y79725D01*
X60690Y79786D01*
X60933Y79968D01*
X61237Y80090D01*
X61480Y80272D01*
X61663Y80333D01*
X61906Y80516D01*
X62089Y80576D01*
X62332Y80759D01*
X62514Y80820D01*
X62757Y81002D01*
X63062Y81124D01*
X63305Y81306D01*
X63487Y81367D01*
X63731Y81550D01*
X63913Y81610D01*
X64156Y81793D01*
X64339Y81854D01*
X64582Y82036D01*
X64886Y82158D01*
X65130Y82340D01*
X65312Y82401D01*
X65555Y82583D01*
X65738Y82644D01*
X65981Y82827D01*
X66163Y82887D01*
X66407Y83070D01*
X66711Y83192D01*
X66954Y83374D01*
X67137Y83435D01*
X67380Y83617D01*
X67562Y83678D01*
X67806Y83861D01*
X67988Y83922D01*
X68231Y84104D01*
X68414Y84165D01*
X68657Y84347D01*
X68961Y84469D01*
X69083Y84591D01*
X69204D01*
Y79543D01*
X68900Y79421D01*
G37*
G36*
G01X68596Y45241D02*
X68535Y45301D01*
X67745Y45362D01*
X67684Y45423D01*
X66954Y45484D01*
X66893Y45544D01*
X66163Y45606D01*
X66103Y45666D01*
X65373Y45727D01*
X65312Y45788D01*
X64582Y45849D01*
X64521Y45909D01*
X63792Y45970D01*
X63731Y46031D01*
X62940Y46092D01*
X62879Y46153D01*
X62150Y46214D01*
X62089Y46274D01*
X61359Y46335D01*
X61298Y46396D01*
X60568Y46457D01*
X60507Y46518D01*
X59778Y46578D01*
X59717Y46639D01*
X58987Y46700D01*
X58926Y46761D01*
X58135Y46822D01*
X58074Y46883D01*
X57345Y46943D01*
X57284Y47004D01*
X56554Y47065D01*
X56493Y47126D01*
X56189D01*
Y51626D01*
X56432Y51748D01*
X56676Y51931D01*
X56980Y52052D01*
X57223Y52235D01*
X57527Y52356D01*
X57770Y52539D01*
X58074Y52661D01*
X58318Y52843D01*
X58622Y52965D01*
X58865Y53147D01*
X59169Y53269D01*
X59413Y53451D01*
X59595Y53512D01*
X59838Y53694D01*
X60143Y53816D01*
X60386Y53998D01*
X60690Y54120D01*
X60933Y54303D01*
X61237Y54424D01*
X61480Y54607D01*
X61785Y54728D01*
X62028Y54911D01*
X62332Y55032D01*
X62575Y55215D01*
X62757Y55276D01*
X63001Y55458D01*
X63305Y55580D01*
X63548Y55762D01*
X63913Y55945D01*
X63852Y56006D01*
X63366Y56066D01*
X62636Y56127D01*
X62271Y56188D01*
X61420Y56249D01*
X61359Y56309D01*
X60264Y56370D01*
X60203Y56431D01*
X59109Y56492D01*
X59048Y56553D01*
X57892Y56614D01*
X57831Y56674D01*
X56737Y56735D01*
X56676Y56796D01*
X56189D01*
Y61236D01*
X56432Y61357D01*
X56676Y61540D01*
X56858Y61601D01*
X57102Y61783D01*
X57284Y61844D01*
X57527Y62027D01*
X57709Y62087D01*
X57953Y62270D01*
X58135Y62331D01*
X58379Y62513D01*
X58561Y62574D01*
X58804Y62756D01*
X58987Y62817D01*
X59230Y63000D01*
X59413Y63061D01*
X59656Y63243D01*
X59838Y63304D01*
X60081Y63486D01*
X60386Y63608D01*
X60629Y63791D01*
X60811Y63851D01*
X61055Y64033D01*
X61237Y64094D01*
X61480Y64277D01*
X61663Y64338D01*
X61906Y64520D01*
X62089Y64581D01*
X62332Y64763D01*
X62514Y64824D01*
X62757Y65007D01*
X62940Y65068D01*
X63183Y65250D01*
X63366Y65311D01*
X63609Y65493D01*
X63792Y65554D01*
X64035Y65737D01*
X64217Y65797D01*
X64461Y65980D01*
X64765Y66102D01*
X65008Y66284D01*
X65191Y66345D01*
X65434Y66527D01*
X65616Y66588D01*
X65859Y66770D01*
X66042Y66831D01*
X66285Y67014D01*
X66468Y67074D01*
X66711Y67257D01*
X66893Y67318D01*
X67137Y67500D01*
X67319Y67561D01*
X67562Y67744D01*
X67745Y67804D01*
X67988Y67987D01*
X68170Y68048D01*
X68414Y68230D01*
X68718Y68352D01*
X68961Y68534D01*
X69083Y68595D01*
X69144D01*
Y63547D01*
X68657Y63304D01*
X68414Y63243D01*
X68110Y63061D01*
X67867Y63000D01*
X67684Y62878D01*
X67441Y62817D01*
X67137Y62635D01*
X66893Y62574D01*
X66589Y62391D01*
X66346Y62331D01*
X66163Y62209D01*
X65920Y62148D01*
X65616Y61966D01*
X65373Y61905D01*
X65069Y61722D01*
X64826Y61662D01*
X64643Y61540D01*
X64400Y61479D01*
X64096Y61297D01*
X63852Y61236D01*
X63548Y61054D01*
X63305Y60993D01*
X63122Y60871D01*
X62879Y60810D01*
X62575Y60628D01*
X62332Y60567D01*
X62028Y60385D01*
X61785Y60324D01*
X61602Y60202D01*
X61359Y60141D01*
X61055Y59959D01*
X61115Y59898D01*
X62089Y59837D01*
X62454Y59776D01*
X63427Y59715D01*
X63792Y59655D01*
X64765Y59594D01*
X65130Y59533D01*
X66103Y59472D01*
X66468Y59411D01*
X67441Y59350D01*
X67806Y59290D01*
X68779Y59229D01*
X69144Y59168D01*
Y54667D01*
X69083D01*
X68839Y54485D01*
X68414Y54303D01*
X68170Y54120D01*
X67745Y53938D01*
X67502Y53755D01*
X67076Y53573D01*
X66833Y53390D01*
X66528Y53269D01*
X66285Y53086D01*
X65859Y52904D01*
X65616Y52721D01*
X65191Y52539D01*
X64947Y52356D01*
X64521Y52174D01*
X64278Y51991D01*
X63974Y51870D01*
X63731Y51687D01*
X63305Y51505D01*
X63062Y51322D01*
X62636Y51140D01*
X62393Y50957D01*
X61967Y50775D01*
X61724Y50593D01*
X61420Y50471D01*
X61176Y50289D01*
X60933Y50167D01*
X60994Y50106D01*
X62332Y50045D01*
X63062Y49984D01*
X64400Y49924D01*
X65130Y49863D01*
X66468Y49802D01*
X67319Y49741D01*
X68535Y49680D01*
X69144Y49620D01*
Y45180D01*
X68596Y45241D01*
G37*
G36*
G01X75591Y42321D02*
X75530Y41835D01*
X75408Y41652D01*
X75347Y41409D01*
X75226Y41166D01*
X74982Y40861D01*
Y40801D01*
X74252Y40132D01*
X74192D01*
X73948Y39949D01*
X73705Y39828D01*
X73401Y39767D01*
X73340Y39706D01*
X72732Y39645D01*
X71941Y39706D01*
X71880Y39767D01*
X71637Y39828D01*
X71394Y40010D01*
X71333D01*
X70846Y40557D01*
Y40618D01*
X70725Y40740D01*
X70664Y40983D01*
X70603Y41044D01*
X70543Y41531D01*
X70481Y41591D01*
X70543Y42565D01*
X70603Y42625D01*
X70664Y42930D01*
X70725Y42990D01*
X70786Y43233D01*
X70907Y43477D01*
X71211Y43842D01*
Y43902D01*
X71941Y44572D01*
X72124Y44632D01*
X72367Y44815D01*
X72610Y44876D01*
X72671Y44937D01*
X73158Y44997D01*
X73219Y45058D01*
X74131Y44997D01*
X74192Y44937D01*
X74435Y44876D01*
X74678Y44754D01*
X75165Y44328D01*
X75347Y44085D01*
X75530Y43720D01*
X75591Y43294D01*
X75651Y43233D01*
Y42382D01*
X75591Y42321D01*
G37*
G36*
G01X68779Y38794D02*
X68718Y38733D01*
X68231Y38672D01*
X68170Y38611D01*
X67684Y38550D01*
X67623Y38490D01*
X67076Y38429D01*
X67015Y38368D01*
X66528Y38307D01*
X66468Y38246D01*
X65981Y38185D01*
X65920Y38125D01*
X65373Y38064D01*
X65312Y38003D01*
X64826Y37942D01*
X64765Y37881D01*
X64278Y37820D01*
X64217Y37760D01*
X63670Y37699D01*
X63609Y37638D01*
X63122Y37577D01*
X63062Y37517D01*
X62575Y37456D01*
X62514Y37395D01*
X61967Y37334D01*
X61906Y37273D01*
X61420Y37212D01*
X61359Y37152D01*
X60872Y37091D01*
X60811Y37030D01*
X60264Y36969D01*
X60203Y36908D01*
X59717Y36848D01*
X59656Y36787D01*
X59169Y36726D01*
X59109Y36665D01*
X58561Y36604D01*
X58500Y36543D01*
X58014Y36483D01*
X57953Y36422D01*
X57467Y36361D01*
X57406Y36300D01*
X56858Y36239D01*
X56797Y36178D01*
X56311Y36118D01*
X56250Y36057D01*
X56189D01*
Y41409D01*
X56554Y41470D01*
X56615Y41531D01*
X57102Y41591D01*
X57162Y41652D01*
X57709Y41713D01*
X57770Y41774D01*
X58257Y41835D01*
X58318Y41895D01*
X58804Y41956D01*
X58865Y42017D01*
X59413Y42078D01*
X59473Y42139D01*
X59960Y42200D01*
X60021Y42260D01*
X60507Y42321D01*
X60568Y42382D01*
X61115Y42443D01*
X61176Y42504D01*
X61663Y42565D01*
X61724Y42625D01*
X62210Y42686D01*
X62271Y42747D01*
X62819Y42808D01*
X62879Y42869D01*
X63366Y42930D01*
X63427Y42990D01*
X63913Y43051D01*
X63974Y43112D01*
X64461Y43173D01*
X64521Y43233D01*
X65069Y43294D01*
X65130Y43355D01*
X65616Y43416D01*
X65677Y43477D01*
X66163Y43537D01*
X66224Y43598D01*
X66772Y43659D01*
X66833Y43720D01*
X67319Y43781D01*
X67380Y43842D01*
X67867Y43902D01*
X67927Y43963D01*
X68475Y44024D01*
X68535Y44085D01*
X69022Y44146D01*
X69083Y44207D01*
X69144D01*
Y38854D01*
X68779Y38794D01*
G37*
G36*
G01X68414Y14527D02*
X67927Y14588D01*
X67867Y14648D01*
X67137Y14709D01*
X67076Y14770D01*
X66285Y14831D01*
X66224Y14892D01*
X65494Y14953D01*
X65434Y15013D01*
X64704Y15074D01*
X64643Y15135D01*
X63913Y15196D01*
X63852Y15257D01*
X63122Y15317D01*
X63062Y15378D01*
X62271Y15439D01*
X62210Y15500D01*
X61480Y15561D01*
X61420Y15622D01*
X60690Y15682D01*
X60629Y15743D01*
X59899Y15804D01*
X59838Y15865D01*
X59109Y15926D01*
X59048Y15987D01*
X58318Y16047D01*
X58257Y16108D01*
X57467Y16169D01*
X57406Y16230D01*
X56676Y16291D01*
X56615Y16352D01*
X56189Y16412D01*
Y20852D01*
X56432Y21035D01*
X56737Y21156D01*
X56980Y21339D01*
X57284Y21460D01*
X57527Y21643D01*
X57709Y21704D01*
X57953Y21886D01*
X58257Y22007D01*
X58500Y22190D01*
X58804Y22312D01*
X59048Y22494D01*
X59352Y22616D01*
X59595Y22798D01*
X59778Y22859D01*
X60021Y23041D01*
X60325Y23163D01*
X60568Y23346D01*
X60872Y23467D01*
X61115Y23650D01*
X61420Y23771D01*
X61663Y23954D01*
X61967Y24076D01*
X62210Y24258D01*
X62393Y24319D01*
X62636Y24501D01*
X62940Y24623D01*
X63183Y24805D01*
X63487Y24927D01*
X63731Y25109D01*
X63792D01*
X63913Y25231D01*
X63852Y25292D01*
X62757Y25353D01*
X62697Y25413D01*
X61602Y25474D01*
X61541Y25535D01*
X60446Y25596D01*
X60386Y25657D01*
X59230Y25718D01*
X59169Y25778D01*
X58074Y25839D01*
X58014Y25900D01*
X56919Y25961D01*
X56858Y26022D01*
X56189Y26082D01*
Y30522D01*
X56493Y30644D01*
X56737Y30826D01*
X56919Y30887D01*
X57162Y31070D01*
X57345Y31130D01*
X57588Y31313D01*
X57770Y31374D01*
X58014Y31556D01*
X58318Y31678D01*
X58561Y31860D01*
X58744Y31921D01*
X58987Y32104D01*
X59169Y32165D01*
X59413Y32347D01*
X59595Y32407D01*
X59838Y32590D01*
X60021Y32651D01*
X60264Y32833D01*
X60446Y32894D01*
X60690Y33077D01*
X60872Y33137D01*
X61115Y33320D01*
X61298Y33381D01*
X61541Y33563D01*
X61724Y33624D01*
X61967Y33807D01*
X62271Y33928D01*
X62514Y34111D01*
X62697Y34171D01*
X62940Y34354D01*
X63122Y34415D01*
X63366Y34597D01*
X63548Y34658D01*
X63792Y34841D01*
X63974Y34901D01*
X64217Y35084D01*
X64400Y35144D01*
X64643Y35327D01*
X64826Y35388D01*
X65069Y35570D01*
X65251Y35631D01*
X65494Y35813D01*
X65677Y35874D01*
X65920Y36057D01*
X66224Y36178D01*
X66468Y36361D01*
X66650Y36422D01*
X66893Y36604D01*
X67076Y36665D01*
X67319Y36848D01*
X67502Y36908D01*
X67745Y37091D01*
X67927Y37152D01*
X68170Y37334D01*
X68353Y37395D01*
X68596Y37577D01*
X68779Y37638D01*
X69022Y37820D01*
X69083D01*
X69144Y37881D01*
Y32772D01*
X68900Y32712D01*
X68475Y32469D01*
X68231Y32407D01*
X67927Y32225D01*
X67684Y32165D01*
X67502Y32043D01*
X67258Y31982D01*
X66954Y31800D01*
X66711Y31739D01*
X66407Y31556D01*
X66163Y31495D01*
X65981Y31374D01*
X65738Y31313D01*
X65434Y31130D01*
X65191Y31070D01*
X64886Y30887D01*
X64643Y30826D01*
X64461Y30705D01*
X64217Y30644D01*
X63913Y30461D01*
X63670Y30401D01*
X63366Y30218D01*
X63122Y30157D01*
X62940Y30036D01*
X62697Y29975D01*
X62393Y29793D01*
X62150Y29731D01*
X61845Y29549D01*
X61602Y29488D01*
X61420Y29367D01*
X61176Y29306D01*
X61055Y29184D01*
X61115Y29124D01*
X62332Y29063D01*
X62393Y29002D01*
X63670Y28941D01*
X63731Y28880D01*
X65008Y28819D01*
X65069Y28759D01*
X66407Y28698D01*
X66468Y28637D01*
X67745Y28576D01*
X67806Y28515D01*
X69083Y28454D01*
X69144Y28394D01*
Y23893D01*
X68718Y23711D01*
X68475Y23528D01*
X68049Y23346D01*
X67806Y23163D01*
X67380Y22981D01*
X67137Y22798D01*
X66711Y22616D01*
X66468Y22433D01*
X66163Y22312D01*
X65920Y22129D01*
X65494Y21947D01*
X65251Y21764D01*
X64826Y21582D01*
X64582Y21399D01*
X64278Y21278D01*
X64035Y21095D01*
X63609Y20913D01*
X63366Y20730D01*
X62940Y20548D01*
X62697Y20365D01*
X62271Y20183D01*
X62028Y20000D01*
X61724Y19879D01*
X61480Y19696D01*
X61055Y19514D01*
X60933Y19393D01*
X60994Y19331D01*
X62940Y19271D01*
X63001Y19210D01*
X65008Y19149D01*
X65069Y19088D01*
X67076Y19028D01*
X67137Y18967D01*
X69144Y18906D01*
Y14405D01*
X68414Y14527D01*
G37*
G36*
G01X48298Y15476D02*
X20698D01*
Y153276D01*
X48298D01*
Y15476D01*
G37*
G36*
G01X71637Y116885D02*
X71394Y117007D01*
Y116460D01*
X71455Y116399D01*
X71880Y116217D01*
X72124Y116034D01*
X72245D01*
X72306Y115852D01*
X72367Y115426D01*
X71394D01*
Y115000D01*
X73190D01*
Y115426D01*
X72732D01*
Y115730D01*
X72793Y116338D01*
X72975Y116399D01*
X73340Y116338D01*
Y116156D01*
X73401Y116095D01*
Y115426D01*
X73191D01*
Y115000D01*
X73766D01*
Y116156D01*
X73705Y116520D01*
X73522Y116764D01*
X73280Y116825D01*
X73219Y116885D01*
X72854Y116825D01*
X72550Y116581D01*
X72489Y116338D01*
X72428Y116277D01*
X72306Y116399D01*
Y116460D01*
X72245Y116520D01*
X72063Y116642D01*
X71880Y116703D01*
X71637Y116885D01*
G37*
G36*
G01X70907Y117372D02*
X70664Y117068D01*
X70603Y116825D01*
X70481Y116642D01*
X70421Y115608D01*
X70481Y115548D01*
X70543Y115183D01*
X70725Y114818D01*
X70907Y114574D01*
X71394Y114149D01*
X71880Y113906D01*
X72793Y113844D01*
X72799Y113845D01*
Y114230D01*
X72610Y114209D01*
X72002Y114270D01*
X71759Y114392D01*
X71455Y114635D01*
X71394D01*
X71029Y115061D01*
X70907Y115304D01*
X70846Y115730D01*
X70786Y115791D01*
X70846Y116520D01*
X70907Y116581D01*
X70968Y116825D01*
X71272Y117190D01*
X71759Y117615D01*
X72002Y117676D01*
X72063Y117737D01*
X72489Y117798D01*
X73097Y117737D01*
X73158Y117676D01*
X73401Y117615D01*
X73766Y117311D01*
X73887D01*
Y117190D01*
X74192Y116825D01*
Y116703D01*
X74252Y116642D01*
X74313Y116277D01*
X74374Y116217D01*
X74313Y115487D01*
X74252Y115426D01*
X74192Y115183D01*
X74009Y114939D01*
Y114878D01*
X73522Y114453D01*
X73158Y114270D01*
X72800Y114230D01*
Y113845D01*
X73280Y113906D01*
X73766Y114149D01*
X74009Y114331D01*
X74435Y114818D01*
X74617Y115183D01*
X74678Y115548D01*
X74739Y115608D01*
Y116399D01*
X74678Y116460D01*
X74617Y116825D01*
X74496Y117068D01*
X74252Y117372D01*
Y117433D01*
X73766Y117859D01*
X73522Y117980D01*
X73280Y118041D01*
X73219Y118102D01*
X72124Y118163D01*
X72063Y118102D01*
X71759Y118041D01*
X71394Y117859D01*
X70907Y117433D01*
Y117372D01*
G37*
G36*
G01X69387Y109587D02*
X69326Y108857D01*
X69265Y108796D01*
X69204Y108371D01*
X69144Y108310D01*
X69083Y108006D01*
X68961Y107824D01*
X68900Y107580D01*
X68596Y106972D01*
X68353Y106668D01*
Y106607D01*
X68049Y106242D01*
Y106181D01*
X67137Y105269D01*
X67197Y105208D01*
X67623Y105269D01*
X67684Y105330D01*
X68170Y105391D01*
X68231Y105452D01*
X68718Y105512D01*
X68779Y105573D01*
X69083Y105634D01*
X69144D01*
Y101012D01*
X69083Y100951D01*
X68596Y100890D01*
X68535Y100829D01*
X67988Y100769D01*
X67927Y100707D01*
X67441Y100647D01*
X67380Y100586D01*
X66893Y100525D01*
X66833Y100464D01*
X66285Y100404D01*
X66224Y100343D01*
X65738Y100282D01*
X65677Y100221D01*
X65191Y100160D01*
X65130Y100099D01*
X64643Y100039D01*
X64582Y99978D01*
X64035Y99917D01*
X63974Y99856D01*
X63487Y99795D01*
X63427Y99735D01*
X62940Y99674D01*
X62879Y99613D01*
X62332Y99552D01*
X62271Y99491D01*
X61785Y99430D01*
X61724Y99370D01*
X61237Y99309D01*
X61176Y99248D01*
X60629Y99187D01*
X60568Y99126D01*
X60081Y99065D01*
X60021Y99005D01*
X59534Y98944D01*
X59473Y98883D01*
X58987Y98822D01*
X58926Y98761D01*
X58379Y98700D01*
X58318Y98640D01*
X57831Y98579D01*
X57770Y98518D01*
X57284Y98457D01*
X57223Y98396D01*
X56676Y98336D01*
X56615Y98275D01*
X56189Y98214D01*
Y103201D01*
X56554Y103262D01*
X56615Y103323D01*
X57162Y103383D01*
X57223Y103444D01*
X57709Y103505D01*
X57770Y103566D01*
X58257Y103627D01*
X58318Y103688D01*
X58804Y103748D01*
X58865Y103809D01*
X59352Y103870D01*
X59413Y103931D01*
X59960Y103992D01*
X60021Y104053D01*
X60507Y104113D01*
X60568Y104174D01*
X61055Y104235D01*
X61115Y104296D01*
X61602Y104357D01*
X61663Y104418D01*
X62150Y104478D01*
X62210Y104539D01*
X62636Y104600D01*
X62697Y104661D01*
X63001Y104722D01*
X63062Y104783D01*
X63305Y104843D01*
X63366Y104904D01*
X63609Y104965D01*
X63670Y105026D01*
X63913Y105087D01*
X64156Y105269D01*
X64339Y105330D01*
X64643Y105573D01*
X64704D01*
X65191Y105999D01*
Y106060D01*
X65555Y106485D01*
X65738Y106850D01*
X65798Y107337D01*
X65859Y107398D01*
X65798Y108006D01*
X65616Y108249D01*
Y108371D01*
X65494D01*
X65373Y108493D01*
X65008Y108553D01*
X64947Y108614D01*
X64217Y108553D01*
X64156Y108493D01*
X63548Y108431D01*
X63487Y108371D01*
X62940Y108310D01*
X62879Y108249D01*
X62393Y108188D01*
X62332Y108128D01*
X61785Y108067D01*
X61724Y108006D01*
X61237Y107945D01*
X61176Y107884D01*
X60690Y107824D01*
X60629Y107763D01*
X60081Y107702D01*
X60021Y107641D01*
X59534Y107580D01*
X59473Y107519D01*
X58926Y107459D01*
X58865Y107398D01*
X58379Y107337D01*
X58318Y107276D01*
X57831Y107215D01*
X57770Y107154D01*
X57223Y107094D01*
X57162Y107033D01*
X56676Y106972D01*
X56615Y106911D01*
X56189Y106850D01*
Y111837D01*
X56676Y111898D01*
X56737Y111959D01*
X57223Y112020D01*
X57284Y112081D01*
X57831Y112142D01*
X57892Y112202D01*
X58379Y112263D01*
X58439Y112324D01*
X58987Y112385D01*
X59048Y112446D01*
X59534Y112507D01*
X59595Y112567D01*
X60081Y112628D01*
X60143Y112689D01*
X60690Y112750D01*
X60750Y112811D01*
X61237Y112871D01*
X61298Y112932D01*
X61845Y112993D01*
X61906Y113054D01*
X62393Y113115D01*
X62454Y113176D01*
X63001Y113236D01*
X63062Y113297D01*
X63548Y113358D01*
X63609Y113419D01*
X64156Y113480D01*
X64217Y113541D01*
X64826Y113601D01*
X64886Y113662D01*
X65616Y113723D01*
X65677Y113784D01*
X67258Y113723D01*
X67319Y113662D01*
X67562Y113601D01*
X67623Y113541D01*
X67745D01*
X67988Y113358D01*
X68049D01*
X68535Y112932D01*
X68961Y112446D01*
X69204Y111959D01*
X69265Y111655D01*
X69326Y111594D01*
X69387Y110986D01*
X69448Y110925D01*
Y109648D01*
X69387Y109587D01*
G37*
G36*
G01Y94139D02*
X69326Y93409D01*
X69265Y93348D01*
X69204Y92983D01*
X69144Y92923D01*
X69083Y92619D01*
X69022Y92558D01*
X68961Y92315D01*
X68900Y92254D01*
X68839Y92011D01*
X68718Y91767D01*
X68535Y91524D01*
Y91463D01*
X68292Y91159D01*
Y91098D01*
X67867Y90612D01*
Y90551D01*
X67197Y89882D01*
X67258Y89821D01*
X67745Y89882D01*
X67806Y89943D01*
X68292Y90004D01*
X68353Y90064D01*
X68839Y90125D01*
X68900Y90186D01*
X69144D01*
Y85564D01*
X68718Y85503D01*
X68657Y85442D01*
X68110Y85381D01*
X68049Y85320D01*
X67562Y85259D01*
X67502Y85199D01*
X67015Y85138D01*
X66954Y85077D01*
X66407Y85016D01*
X66346Y84956D01*
X65859Y84894D01*
X65798Y84834D01*
X65312Y84773D01*
X65251Y84712D01*
X64765Y84651D01*
X64704Y84591D01*
X64156Y84530D01*
X64096Y84469D01*
X63609Y84408D01*
X63548Y84347D01*
X63062Y84287D01*
X63001Y84226D01*
X62454Y84165D01*
X62393Y84104D01*
X61906Y84043D01*
X61845Y83982D01*
X61359Y83922D01*
X61298Y83861D01*
X60750Y83800D01*
X60690Y83739D01*
X60203Y83678D01*
X60143Y83617D01*
X59656Y83557D01*
X59595Y83496D01*
X59109Y83435D01*
X59048Y83374D01*
X58500Y83313D01*
X58439Y83252D01*
X57953Y83192D01*
X57892Y83131D01*
X57406Y83070D01*
X57345Y83009D01*
X56797Y82948D01*
X56737Y82887D01*
X56250Y82827D01*
X56189Y82766D01*
Y87814D01*
X56737Y87875D01*
X56797Y87935D01*
X57284Y87996D01*
X57345Y88057D01*
X57831Y88118D01*
X57892Y88179D01*
X58379Y88240D01*
X58439Y88300D01*
X58926Y88361D01*
X58987Y88422D01*
X59534Y88483D01*
X59595Y88544D01*
X60081Y88605D01*
X60143Y88665D01*
X60629Y88726D01*
X60690Y88787D01*
X61176Y88848D01*
X61237Y88909D01*
X61724Y88970D01*
X61785Y89030D01*
X62271Y89091D01*
X62332Y89152D01*
X62697Y89213D01*
X62757Y89274D01*
X63062Y89334D01*
X63122Y89395D01*
X63427Y89456D01*
X64278Y89882D01*
X64582Y90125D01*
X64643D01*
X65251Y90672D01*
X65494Y90976D01*
X65738Y91463D01*
X65798Y91950D01*
X65859Y92011D01*
X65798Y92619D01*
X65494Y92983D01*
X65312Y93105D01*
X64826Y93166D01*
X64035Y93105D01*
X63974Y93044D01*
X63427Y92983D01*
X63366Y92923D01*
X62819Y92862D01*
X62757Y92801D01*
X62210Y92740D01*
X62150Y92680D01*
X61663Y92619D01*
X61602Y92558D01*
X61055Y92497D01*
X60994Y92436D01*
X60507Y92375D01*
X60446Y92315D01*
X59960Y92254D01*
X59899Y92193D01*
X59352Y92132D01*
X59291Y92071D01*
X58804Y92011D01*
X58744Y91950D01*
X58196Y91889D01*
X58135Y91828D01*
X57649Y91767D01*
X57588Y91706D01*
X57102Y91646D01*
X57041Y91585D01*
X56493Y91524D01*
X56432Y91463D01*
X56189D01*
Y96389D01*
X56493Y96450D01*
X56554Y96511D01*
X57102Y96572D01*
X57162Y96633D01*
X57649Y96694D01*
X57709Y96754D01*
X58257Y96815D01*
X58318Y96876D01*
X58804Y96937D01*
X58865Y96998D01*
X59352Y97058D01*
X59413Y97119D01*
X59960Y97180D01*
X60021Y97241D01*
X60507Y97302D01*
X60568Y97363D01*
X61115Y97423D01*
X61176Y97484D01*
X61663Y97545D01*
X61724Y97606D01*
X62210Y97667D01*
X62271Y97728D01*
X62819Y97788D01*
X62879Y97849D01*
X63366Y97910D01*
X63427Y97971D01*
X63974Y98031D01*
X64035Y98093D01*
X64643Y98153D01*
X64704Y98214D01*
X65373Y98275D01*
X65434Y98336D01*
X66407Y98396D01*
X67137Y98336D01*
X67197Y98275D01*
X67502Y98214D01*
X67562Y98153D01*
X67806Y98093D01*
X68049Y97910D01*
X68110D01*
X68596Y97484D01*
X68961Y97058D01*
X69144Y96694D01*
X69204Y96450D01*
X69265Y96389D01*
X69326Y95964D01*
X69387Y95903D01*
X69448Y94930D01*
Y94200D01*
X69387Y94139D01*
G37*
G36*
G01X142435Y47038D02*
G02I-11811J0D01*
G37*
G36*
G01X88839Y35330D02*
X83839D01*
Y55330D01*
X88839D01*
Y35330D01*
G37*
G36*
G01X160657Y61132D02*
X162457D01*
Y65632D01*
X160657D01*
Y61132D01*
G37*
G36*
G01X156157Y52132D02*
X157957D01*
Y55732D01*
X156157D01*
Y52132D01*
G37*
G36*
G01Y61132D02*
X157957D01*
Y63832D01*
X156157D01*
Y61132D01*
G37*
G36*
G01X151657Y55732D02*
X162457D01*
Y57532D01*
X151657D01*
Y55732D01*
G37*
G36*
G01Y59332D02*
X162457D01*
Y61132D01*
X151657D01*
Y59332D01*
G37*
G36*
G01Y50332D02*
X162457D01*
Y52132D01*
X151657D01*
Y50332D01*
G37*
%LPC*%
G75*
G36*
G01X119994Y47038D02*
X120199Y49113D01*
X120804Y51108D01*
X121784Y52943D01*
X122664Y54012D01*
X125104Y51572D01*
Y51142D01*
X125112Y51044D01*
X125324Y50343D01*
X125499Y50018D01*
X125104D01*
Y48418D01*
X128259D01*
X130976Y45701D01*
X130644Y45293D01*
X130303Y44657D01*
X130104Y44001D01*
Y41443D01*
X125104D01*
Y39873D01*
X136804D01*
X137598Y39078D01*
X136529Y38198D01*
X134694Y37218D01*
X132699Y36613D01*
X130624Y36408D01*
X128549Y36613D01*
X126554Y37218D01*
X124719Y38198D01*
X123109Y39523D01*
X121784Y41133D01*
X120804Y42968D01*
X120199Y44963D01*
X119994Y47038D01*
G37*
G36*
G01X123649Y54997D02*
X124719Y55878D01*
X126554Y56858D01*
X128549Y57463D01*
X130624Y57668D01*
X132699Y57463D01*
X134694Y56858D01*
X136529Y55878D01*
X138139Y54553D01*
X139464Y52943D01*
X140444Y51108D01*
X141049Y49113D01*
X141254Y47038D01*
X141049Y44963D01*
X140444Y42968D01*
X139464Y41133D01*
X138582Y40062D01*
X137339Y41304D01*
Y43693D01*
X137304Y43967D01*
X137094Y44658D01*
X136754Y45293D01*
X136299Y45853D01*
X135739Y46308D01*
X135104Y46648D01*
X134414Y46858D01*
X133699Y46928D01*
X132984Y46858D01*
X132294Y46648D01*
X132101Y46544D01*
X130227Y48418D01*
X137144D01*
Y50018D01*
X133089D01*
X133264Y50343D01*
X133474Y51038D01*
X133544Y51763D01*
X133474Y52488D01*
X133264Y53183D01*
X132919Y53823D01*
X132459Y54383D01*
X131899Y54843D01*
X131259Y55188D01*
X130566Y55397D01*
X129839Y55468D01*
X128749D01*
X128024Y55398D01*
X127329Y55188D01*
X126689Y54843D01*
X126129Y54383D01*
X125669Y53823D01*
X125373Y53273D01*
X123649Y54997D01*
G37*
G36*
G01X126573Y52073D02*
X126584Y52193D01*
X126714Y52609D01*
X126916Y52991D01*
X127193Y53327D01*
X127527Y53600D01*
X127908Y53801D01*
X128322Y53929D01*
X128749Y53968D01*
X129839D01*
X130269Y53930D01*
X130684Y53798D01*
X131064Y53598D01*
X131399Y53323D01*
X131675Y52988D01*
X131875Y52606D01*
X132004Y52191D01*
X132044Y51764D01*
X132004Y51334D01*
X131874Y50918D01*
X131674Y50538D01*
X131399Y50203D01*
X131174Y50018D01*
X128627D01*
X126573Y52073D01*
G37*
G36*
G01X131679Y41443D02*
Y44053D01*
X131689Y44083D01*
X131889Y44463D01*
X132032Y44645D01*
X135234Y41443D01*
X131679D01*
G37*
G36*
G01X133260Y45384D02*
X133274Y45388D01*
X133699Y45428D01*
X134124Y45388D01*
X134529Y45263D01*
X134909Y45063D01*
X135239Y44793D01*
X135509Y44463D01*
X135709Y44083D01*
X135739Y43998D01*
Y42904D01*
X133260Y45384D01*
G37*
%LPD*%
G75*
G54D10*
G01X-351984Y-328833D02*
X-383984D01*
G01X-351984Y-344833D02*
Y-424833D01*
G01D02*
X998716D01*
G01X-355984Y-328833D02*
G02I-12000J0D01*
G01X-361134D02*
G02I-6850J0D01*
G01X-367984Y-344833D02*
Y-312833D01*
G01X-351984Y-344833D02*
X998716D01*
G01X-351984Y-380333D02*
X998716D01*
G01X211216Y-344833D02*
Y-424833D01*
G01X208500Y249139D02*
Y277399D01*
X208501Y277400D01*
X226999D01*
X227000Y277399D01*
Y15000D01*
X171500D01*
Y179800D01*
G01D02*
X208500D01*
Y237745D01*
G01X348716Y-344833D02*
Y-424833D01*
G01X463716Y-344833D02*
Y-424833D01*
G01X631216Y-344833D02*
Y-424833D01*
G01X801216Y-344833D02*
Y-424833D01*
G01X998716Y-344833D02*
Y-424833D01*
G01X1026716Y-328833D02*
G02I-12000J0D01*
G01X1021566D02*
G02I-6850J0D01*
G01X1014716Y-344833D02*
Y-312833D01*
G01X1030716Y-328833D02*
X998716D01*
G54D11*
G01X0Y20866D02*
Y-18504D01*
G01X71407Y128987D02*
X89224Y111170D01*
G01X0Y307086D02*
Y346456D01*
G01X64567D02*
Y321260D01*
G01X0Y409449D02*
Y370079D01*
G01X71407Y517570D02*
X89224Y499752D01*
G01X0Y695669D02*
Y735039D01*
G01X64567D02*
Y709842D01*
G01X161271Y128987D02*
X143454Y111170D01*
G01X161271Y517570D02*
X143454Y499753D01*
G01X168110Y346456D02*
Y321260D01*
G01X225227Y354331D02*
X207116D01*
G01X225227Y362205D02*
X207116D01*
G01X168110Y709842D02*
Y735039D01*
G01X232677Y-18504D02*
Y20866D01*
G01X248425Y-18504D02*
Y20866D01*
G01Y346456D02*
Y307086D01*
G01X232677Y346456D02*
Y307086D01*
G01X248425Y370079D02*
Y409449D01*
G01X232677Y370079D02*
Y409449D01*
G01X255876Y354331D02*
X273986D01*
G01X255876Y362205D02*
X273986D01*
G01X232677Y735039D02*
Y695669D01*
G01X248425Y735039D02*
Y695669D01*
G01X312992Y6693D02*
Y-18504D01*
G01X337648Y216782D02*
X319832Y198966D01*
G01X312992Y395275D02*
Y370079D01*
G01X337649Y605365D02*
X319832Y587548D01*
G01X416536Y6693D02*
Y-18504D01*
G01X391880Y216782D02*
X409696Y198966D01*
G01X416536Y370079D02*
Y395275D01*
G01X391879Y605365D02*
X409696Y587548D01*
G01X481103Y20866D02*
Y-18504D01*
G01Y346456D02*
Y307086D01*
G01Y409449D02*
Y370079D01*
G01Y735039D02*
Y695669D01*
G54D12*
G01X168857Y57532D02*
G03I-10900J0D01*
G54D13*
G01X93929Y38500D02*
Y37840D01*
G01X94019Y37940D02*
Y38600D01*
G01X94129Y38690D02*
Y38040D01*
G01X94219Y38140D02*
Y38790D01*
G01X94329Y38890D02*
Y38230D01*
G01X94429Y38330D02*
Y38980D01*
G01X94519Y39080D02*
Y38430D01*
G01X94629Y38520D02*
Y39180D01*
G01X94719Y39270D02*
Y38620D01*
G01X94829Y38710D02*
Y39370D01*
G01X94929Y39470D02*
Y38810D01*
G01X95019Y38910D02*
Y39560D01*
G01X95129Y39660D02*
Y39015D01*
G01Y39010D02*
Y39060D01*
G01X95219Y39100D02*
Y39140D01*
G01Y39100D02*
Y39750D01*
G01X95329Y39850D02*
Y39200D01*
G01X95429Y39300D02*
Y39950D01*
G01X95519Y40050D02*
Y39390D01*
G01X95629Y39490D02*
Y40140D01*
G01X95719Y40240D02*
Y39580D01*
G01X95829Y39680D02*
Y40340D01*
G01X95929Y40430D02*
Y39780D01*
G01X96019Y39880D02*
Y40530D01*
G01X96129Y40620D02*
Y39970D01*
G01X96219Y40070D02*
Y40720D01*
G01X96329Y40820D02*
Y40160D01*
G01X96429Y40260D02*
Y40920D01*
G01X96519Y41010D02*
Y40360D01*
G01X96629Y40450D02*
Y41110D01*
G01X96829Y41300D02*
Y40650D01*
G01X97019Y40840D02*
Y41490D01*
G01X111439Y36200D02*
X111459Y36230D01*
G01X110899Y36200D02*
X111439D01*
G01X110879Y36210D02*
X110899Y36200D01*
G01X110769Y36260D02*
X110879Y36210D01*
G01X110759Y36270D02*
X110769Y36260D01*
G01X105169Y41450D02*
X110759Y36270D01*
G01X111429Y36200D02*
Y36260D01*
G01X111329Y36200D02*
Y36350D01*
G01X111219Y36440D02*
Y36200D01*
G01X111129D02*
Y36540D01*
G01X111019Y36630D02*
Y36200D01*
G01X110929D02*
Y36720D01*
G01X110829Y36820D02*
Y36230D01*
G01X110719Y36300D02*
Y36910D01*
G01X110629Y37000D02*
Y36390D01*
G01X110519Y36480D02*
Y37090D01*
G01X110429Y37190D02*
Y36580D01*
G01X110329Y36670D02*
Y37280D01*
G01X110219Y37370D02*
Y36760D01*
G01X110129Y36850D02*
Y37470D01*
G01X110019Y37560D02*
Y36950D01*
G01X109929Y37040D02*
Y37650D01*
G01X109829Y37750D02*
Y37130D01*
G01X109719Y37230D02*
Y37840D01*
G01X109629Y37930D02*
Y37320D01*
G01X109519Y37410D02*
Y38030D01*
G01X109429Y38120D02*
Y37510D01*
G01X109329Y37600D02*
Y38210D01*
G01X109219Y38310D02*
Y37690D01*
G01X109129Y37780D02*
Y38400D01*
G01X109019Y38490D02*
Y37880D01*
G01X108929Y37970D02*
Y38580D01*
G01X108829Y38680D02*
Y38060D01*
G01X108719Y38160D02*
Y38770D01*
G01X108629Y38860D02*
Y38250D01*
G01X108519Y38340D02*
Y38950D01*
G01X108429Y39050D02*
Y38440D01*
G01X108329Y38530D02*
Y39140D01*
G01X108219Y39230D02*
Y38620D01*
G01X108129Y38710D02*
Y39330D01*
G01X108019Y39420D02*
Y38810D01*
G01X107929Y38900D02*
Y39510D01*
G01X107829Y39610D02*
Y38990D01*
G01X107719Y39080D02*
Y39700D01*
G01X107629Y39790D02*
Y39180D01*
G01X107519Y39270D02*
Y39890D01*
G01X107429Y39980D02*
Y39360D01*
G01X107329Y39450D02*
Y40070D01*
G01X107219Y40170D02*
Y39550D01*
G01X107129Y39640D02*
Y40260D01*
G01X107019Y40350D02*
Y39730D01*
G01X106929Y39820D02*
Y40450D01*
G01X106829Y40540D02*
Y39920D01*
G01X106719Y40010D02*
Y40630D01*
G01X106629Y40720D02*
Y40100D01*
G01X106519Y40200D02*
Y40820D01*
G01X106429Y40910D02*
Y40290D01*
G01X106329Y40380D02*
Y41000D01*
G01X106219Y41100D02*
Y40480D01*
G01X106019Y40660D02*
Y41900D01*
G01X105829Y41910D02*
Y40850D01*
G01X108119Y40600D02*
Y41110D01*
G01X108079Y40560D02*
X108119Y40600D01*
G01X107619Y40560D02*
X108079D01*
G01X107579Y40600D02*
X107619Y40560D01*
G01X108019D02*
Y50810D01*
G01X107829Y50740D02*
Y40560D01*
G01X107629D02*
Y50580D01*
G01X108929Y43210D02*
Y41780D01*
G01X108189Y41200D02*
X108119Y41110D01*
G01X108239Y41220D02*
X108189Y41200D01*
G01X108249Y41220D02*
X108239D01*
G01X108499Y41340D02*
X108249Y41220D01*
G01X108509Y41360D02*
X108499Y41340D01*
G01X108929Y41790D02*
X108509Y41360D01*
G01X108129Y41120D02*
Y41850D01*
G01X108459Y41960D02*
X108529Y42070D01*
G01X108289Y41790D02*
X108459Y41960D01*
G01X108179Y41770D02*
X108289Y41790D01*
G01X108119Y41860D02*
X108179Y41770D01*
G01X108429Y41930D02*
Y41310D01*
G01X108329Y41260D02*
Y41830D01*
G01X108219Y41780D02*
Y41210D01*
G01X108629Y41470D02*
Y43150D01*
G01X108829D02*
Y41680D01*
G01X105229Y42030D02*
X101749Y45260D01*
G01X105229Y42020D02*
Y42030D01*
G01X105279Y41980D02*
X105229Y42020D01*
G01X105339Y41950D02*
X105279Y41980D01*
G01X107469Y41770D02*
X105339Y41950D01*
G01X107579Y41870D02*
X107469Y41770D01*
G01X101429Y42290D02*
Y41820D01*
G01X101629Y41810D02*
Y42270D01*
G01X101829Y42250D02*
Y41790D01*
G01X102019Y41770D02*
Y42240D01*
G01X102219Y42220D02*
Y41750D01*
G01X102429Y41730D02*
Y42200D01*
G01X102629Y42190D02*
Y41720D01*
G01X102829Y41700D02*
Y42170D01*
G01X103019Y42150D02*
Y41680D01*
G01X103219Y41670D02*
Y42140D01*
G01X103429Y42120D02*
Y41650D01*
G01X103629Y41630D02*
Y42100D01*
G01X103829Y42080D02*
Y41620D01*
G01X104019Y41600D02*
Y42070D01*
G01X104219Y42050D02*
Y41580D01*
G01X104329Y41570D02*
Y42080D01*
G01X104629Y42580D02*
Y41550D01*
G01X104829Y41530D02*
Y42400D01*
G01X105139Y41470D02*
X105169Y41450D01*
G01X105039Y41510D02*
X105139Y41470D01*
G01X105029Y41510D02*
X105039D01*
G01X105019D02*
X105029D01*
G01X105019Y42210D02*
Y41510D01*
G01X105219Y41410D02*
Y42030D01*
G01X105329Y41960D02*
Y41310D01*
G01X105429Y41220D02*
Y41950D01*
G01X105519Y41940D02*
Y41130D01*
G01X105629Y41030D02*
Y41930D01*
G01X105719Y41920D02*
Y40940D01*
G01X105929Y40750D02*
Y41900D01*
G01X106129Y41890D02*
Y41410D01*
G01X107579Y41200D02*
Y40600D01*
G01X107489Y41300D02*
X107579Y41200D01*
G01X106139Y41420D02*
X107489Y41300D01*
G01X107519Y41260D02*
Y41820D01*
G01X107429Y41770D02*
Y41310D01*
G01X107329Y41320D02*
Y41790D01*
G01X107219D02*
Y41320D01*
G01X107129Y41330D02*
Y41800D01*
G01X107019Y41810D02*
Y41340D01*
G01X106929Y41350D02*
Y41820D01*
G01X106829Y41830D02*
Y41360D01*
G01X106719Y41370D02*
Y41840D01*
G01X106629D02*
Y41380D01*
G01X106519D02*
Y41850D01*
G01X106429Y41860D02*
Y41400D01*
G01X106329D02*
Y41870D01*
G01X106219Y41880D02*
Y41410D01*
G01X106069Y41250D02*
X111459Y36230D01*
G01X106039Y41360D02*
X106069Y41250D01*
G01X106139Y41420D02*
X106039Y41360D01*
G01X106129Y40570D02*
Y41190D01*
G01X105019Y41510D02*
X99869Y41950D01*
G01X99829Y41960D02*
Y42430D01*
G01X99629Y42440D02*
Y41970D01*
G01X99429Y41990D02*
Y42460D01*
G01X99219Y42480D02*
Y42010D01*
G01X99019Y42030D02*
Y42500D01*
G01X98929Y42540D02*
Y42040D01*
G01X98279Y42050D02*
X98169Y41950D01*
G01X98349Y42080D02*
X98279Y42050D01*
G01X98129Y41900D02*
Y42590D01*
G01X97929D02*
Y41710D01*
G01X97719Y41520D02*
Y42610D01*
G01X97519Y41970D02*
Y41320D01*
G01X97429Y41230D02*
Y41880D01*
G01X97329Y41780D02*
Y41130D01*
G01X97219Y41030D02*
Y41690D01*
G01X97129Y41590D02*
Y40940D01*
G01X96929Y40750D02*
Y41400D01*
G01X96719Y41200D02*
Y40550D01*
G01X100129Y41930D02*
Y42400D01*
G01X100329Y42380D02*
Y41920D01*
G01X100519Y41900D02*
Y42370D01*
G01X100719Y42350D02*
Y41880D01*
G01X100929Y41860D02*
Y42330D01*
G01X101129Y42320D02*
Y41850D01*
G01X101219Y41840D02*
Y42310D01*
G01X101329Y42300D02*
Y41830D01*
G01X101519Y41810D02*
Y42280D01*
G01X101719Y42270D02*
Y41800D01*
G01X101929Y41780D02*
Y42250D01*
G01X102129Y42230D02*
Y41760D01*
G01X102329Y41750D02*
Y42210D01*
G01X102519Y42190D02*
Y41730D01*
G01X102719Y41710D02*
Y42180D01*
G01X102929Y42160D02*
Y41690D01*
G01X103129Y41680D02*
Y42140D01*
G01X103329Y42130D02*
Y41660D01*
G01X103519Y41640D02*
Y42110D01*
G01X103719Y42090D02*
Y41620D01*
G01X103929Y41610D02*
Y42070D01*
G01X104129Y42060D02*
Y41590D01*
G01X104349Y42220D02*
X101409Y44950D01*
G01X104369Y42100D02*
X104349Y42220D01*
G01X104269Y42050D02*
X104369Y42100D01*
G01X101019Y42320D02*
Y41860D01*
G01X100829Y41870D02*
Y42340D01*
G01X100629Y42360D02*
Y41890D01*
G01X100429Y41910D02*
Y42380D01*
G01X100219Y42390D02*
Y41920D01*
G01X100019Y41940D02*
Y42410D01*
G01X99929Y42420D02*
Y41950D01*
G01X98409Y42080D02*
X98349D01*
G01X99869Y41950D02*
X98409Y42080D01*
G01X98329Y42070D02*
Y42750D01*
G01X98149Y42600D02*
X98079Y42580D01*
G01X98229Y42650D02*
X98149Y42600D01*
G01X98019Y42580D02*
Y41810D01*
G01X97829Y41620D02*
Y42600D01*
G01X97519Y42620D02*
Y42120D01*
G01X97559Y42090D02*
X97539Y41990D01*
G01X95119Y42360D02*
Y42470D01*
G01X95129Y42360D02*
X95119D01*
G01X97479Y42160D02*
X95129Y42360D01*
G01X97559Y42090D02*
X97479Y42160D01*
G01X95219Y42460D02*
Y42350D01*
G01Y42355D02*
Y47950D01*
G01X95129Y48015D02*
Y42360D01*
G01X94079Y42600D02*
Y43490D01*
G01X94119Y42560D02*
X94079Y42600D01*
G01X94799Y42560D02*
X94119D01*
G01X94869Y42530D02*
X94799Y42560D01*
G01X95029Y42380D02*
X94869Y42530D01*
G01X95049Y42370D02*
X95029Y42380D01*
G01X95109Y42360D02*
X95049Y42370D01*
G01X94129Y43530D02*
Y42560D01*
G01X94329D02*
Y43530D01*
G01X94519D02*
Y42560D01*
G01X94719D02*
Y43530D01*
G01X95429Y42810D02*
Y42340D01*
G01X95519Y42320D02*
Y42790D01*
G01X95719Y42780D02*
Y42310D01*
G01X95929Y42290D02*
Y42760D01*
G01X96129Y42740D02*
Y42270D01*
G01X96329Y42260D02*
Y42730D01*
G01X96519Y42710D02*
Y42240D01*
G01X96719Y42220D02*
Y42690D01*
G01X96929Y42680D02*
Y42210D01*
G01X97129Y42190D02*
Y42660D01*
G01X97329Y42640D02*
Y42180D01*
G01X98519Y42070D02*
Y42940D01*
G01X98719Y43130D02*
Y42050D01*
G01X99129Y42020D02*
Y42490D01*
G01X98979Y42500D02*
X104269Y42050D01*
G01X104329Y42240D02*
Y42860D01*
G01X104129Y43050D02*
Y42430D01*
G01X103929Y42610D02*
Y43230D01*
G01X104719Y42490D02*
Y41540D01*
G01X104929Y41520D02*
Y42310D01*
G01X105129Y42120D02*
Y41480D01*
G01X108539Y42180D02*
X108529Y42070D01*
G01X108449Y42230D02*
X108539Y42180D01*
G01X108219Y42230D02*
X108449D01*
G01X108119Y42130D02*
X108219Y42230D01*
G01X108119Y41860D02*
Y42130D01*
G01X108519Y42060D02*
Y41370D01*
G01X109509Y42240D02*
X109529Y42270D01*
G01X109479Y42230D02*
X109509Y42240D01*
G01X109279Y42230D02*
X109479D01*
G01X109239Y42220D02*
X109279Y42230D01*
G01X109189Y42200D02*
X109239Y42220D01*
G01X109129Y42150D02*
X109189Y42200D01*
G01X109089Y42060D02*
X109129Y42150D01*
G01X108929Y41790D02*
X109089Y42060D01*
G01X109519Y42270D02*
Y43100D01*
G01X109329Y42230D02*
Y45120D01*
G01X109129Y45110D02*
Y42130D01*
G01X108519Y42180D02*
Y43150D01*
G01X108329D02*
Y42230D01*
G01X108129Y42140D02*
Y43250D01*
G01X99719Y42440D02*
Y41970D01*
G01X99519Y41980D02*
Y42450D01*
G01X99329Y42470D02*
Y42000D01*
G01X98889Y42570D02*
X98919Y42670D01*
G01X98979Y42500D02*
X98889Y42570D01*
G01X94929Y42480D02*
Y48260D01*
G01X95499Y42800D02*
X98079Y42580D01*
G01X95429Y42800D02*
X95499D01*
G01X95339Y42900D02*
X95429Y42800D01*
G01X95339Y47000D02*
Y42900D01*
G01X98219Y42650D02*
Y42000D01*
G01X98429Y42080D02*
Y42840D01*
G01X98229Y42660D02*
Y42650D01*
G01X98239Y42660D02*
X98229D01*
G01X98239D02*
X100929Y45250D01*
G01X100719Y45060D02*
Y44420D01*
G01X100519Y44220D02*
Y44870D01*
G01X100329Y44680D02*
Y44030D01*
G01X100129Y43840D02*
Y44480D01*
G01X100019Y44390D02*
Y43740D01*
G01X100079Y43790D02*
X98919Y42670D01*
G01X98929Y42680D02*
Y43320D01*
G01X98829Y43230D02*
Y42050D01*
G01X98629Y42060D02*
Y43040D01*
G01X99019Y42780D02*
Y43420D01*
G01X99129Y43520D02*
Y42880D01*
G01X99219Y42970D02*
Y43620D01*
G01X99329Y43710D02*
Y43070D01*
G01X99429Y43160D02*
Y43810D01*
G01X99519Y43900D02*
Y43260D01*
G01X99629Y43360D02*
Y44000D01*
G01X99719Y44100D02*
Y43450D01*
G01X99829Y43550D02*
Y44190D01*
G01X99929Y44290D02*
Y43640D01*
G01X101929Y44470D02*
Y45100D01*
G01X102129Y44910D02*
Y44290D01*
G01X102329Y44100D02*
Y44720D01*
G01X102519Y44540D02*
Y43910D01*
G01X102629Y43820D02*
Y44440D01*
G01X102719Y44350D02*
Y43730D01*
G01X102829Y43640D02*
Y44260D01*
G01X102929Y44160D02*
Y43540D01*
G01X103019Y43450D02*
Y44070D01*
G01X103129Y43980D02*
Y43360D01*
G01X103219Y43260D02*
Y43890D01*
G01X103329Y43790D02*
Y43170D01*
G01X103429Y43080D02*
Y43700D01*
G01X103519Y43610D02*
Y42980D01*
G01X103629Y42890D02*
Y43510D01*
G01X103719Y43420D02*
Y42800D01*
G01X103829Y42710D02*
Y43330D01*
G01X104019Y43140D02*
Y42520D01*
G01X104219Y42330D02*
Y42950D01*
G01X104429Y42770D02*
Y41570D01*
G01X104519Y41560D02*
Y42680D01*
G01X103799Y44530D02*
X103759Y44570D01*
G01X108219Y43150D02*
Y42230D01*
G01X108119Y43250D02*
X108219Y43150D01*
G01X108429Y42230D02*
Y43150D01*
G01X109129Y44480D02*
X109019Y44590D01*
G01X109099Y44210D02*
X109129Y44480D01*
G01X109069Y43930D02*
X109099Y44210D01*
G01X109059Y43810D02*
X109069Y43930D01*
G01X109039Y43710D02*
X109059Y43810D01*
G01X108999Y43460D02*
X109039Y43710D01*
G01X108999Y43450D02*
Y43460D01*
G01X108979Y43360D02*
X108999Y43450D01*
G01X108979Y43350D02*
Y43360D01*
G01X108959Y43230D02*
X108979Y43350D01*
G01X108859Y43150D02*
X108959Y43230D01*
G01X108219Y43150D02*
X108859D01*
G01X109529Y43090D02*
Y42270D01*
G01X109519Y43110D02*
X109529Y43090D01*
G01X109509Y43140D02*
X109519Y43110D01*
G01X109489Y43170D02*
X109509Y43140D01*
G01X109469Y43250D02*
X109489Y43170D01*
G01X109479Y43270D02*
X109469Y43250D01*
G01X109519Y43510D02*
X109479Y43270D01*
G01X109589Y44010D02*
X109519Y43510D01*
G01X109599Y44130D02*
X109589Y44010D01*
G01X109599Y44190D02*
Y44130D01*
G01X109619Y44350D02*
X109599Y44190D01*
G01X109629Y44490D02*
X109619Y44350D01*
G01X109019Y41950D02*
Y43600D01*
G01X108719Y43150D02*
Y41580D01*
G01X108119Y43250D02*
Y49090D01*
G01X109629Y47160D02*
Y44470D01*
G01Y44490D02*
X109729Y44590D01*
G01X97629Y42620D02*
Y41420D01*
G01X97429Y42160D02*
Y42630D01*
G01X97219Y42650D02*
Y42180D01*
G01X97019Y42200D02*
Y42670D01*
G01X96829Y42680D02*
Y42210D01*
G01X96629Y42230D02*
Y42700D01*
G01X96429Y42720D02*
Y42250D01*
G01X96219Y42270D02*
Y42730D01*
G01X96019Y42750D02*
Y42290D01*
G01X95829Y42300D02*
Y42770D01*
G01X95629Y42790D02*
Y42320D01*
G01X94829Y42550D02*
Y43600D01*
G01X94119Y43530D02*
X94079Y43490D01*
G01X94759Y43530D02*
X94119D01*
G01X94859Y43630D02*
X94759Y43530D01*
G01X94219D02*
Y42560D01*
G01X94429D02*
Y43530D01*
G01X94629D02*
Y42560D01*
G01X95809Y47100D02*
X95819D01*
G01X95739Y47090D02*
X95809Y47100D01*
G01X95479Y47090D02*
X95739D01*
G01X95459Y47100D02*
X95479Y47090D01*
G01X95339Y47000D02*
X95459Y47100D01*
G01X95829D02*
Y47870D01*
G01X95629Y47830D02*
Y47090D01*
G01X95429Y47070D02*
Y47870D01*
G01X101259Y45710D02*
X101399D01*
G01X98359Y48410D02*
X101259Y45710D01*
G01X101429Y45730D02*
Y44940D01*
G01X101269Y44950D02*
X100079Y43790D01*
G01X101409Y44950D02*
X101269D01*
G01X100219Y43940D02*
Y44580D01*
G01X100429Y44770D02*
Y44130D01*
G01X100629Y44320D02*
Y44970D01*
G01X100829Y45160D02*
Y44510D01*
G01X100929Y45400D02*
X99109Y47080D01*
G01X100929Y45250D02*
Y45400D01*
G01Y44610D02*
Y45250D01*
G01X99129Y47070D02*
Y47700D01*
G01X99329Y47510D02*
Y46880D01*
G01X99519Y46700D02*
Y47330D01*
G01X99719Y47140D02*
Y46510D01*
G01X99829Y46420D02*
Y47050D01*
G01X99929Y46950D02*
Y46320D01*
G01X100019Y46230D02*
Y46860D01*
G01X100129Y46770D02*
Y46140D01*
G01X100219Y46050D02*
Y46680D01*
G01X100329Y46580D02*
Y45950D01*
G01X100429Y45860D02*
Y46490D01*
G01X100519Y46400D02*
Y45770D01*
G01X100629Y45680D02*
Y46310D01*
G01X100719Y46210D02*
Y45580D01*
G01X100829Y45490D02*
Y46120D01*
G01X100929Y46030D02*
Y45380D01*
G01X101219Y45750D02*
Y44900D01*
G01X101329Y44950D02*
Y45710D01*
G01X101519Y45830D02*
Y44840D01*
G01X101629Y44750D02*
Y45930D01*
G01X101719Y46030D02*
Y44660D01*
G01X101829Y44570D02*
Y45190D01*
G01X101749Y45400D02*
X103219Y46830D01*
G01X101749Y45260D02*
Y45400D01*
G01X103129Y46730D02*
Y47370D01*
G01X102929Y47180D02*
Y46540D01*
G01X102829Y46450D02*
Y47080D01*
G01X102719Y46990D02*
Y46350D01*
G01X102629Y46250D02*
Y46890D01*
G01X102519Y46800D02*
Y46160D01*
G01X102429Y46060D02*
Y46700D01*
G01X102329Y46600D02*
Y45960D01*
G01X102219Y45870D02*
Y46510D01*
G01X102129Y46410D02*
Y45770D01*
G01X102019Y45680D02*
Y46310D01*
G01X101929Y46220D02*
Y45580D01*
G01X101829Y45480D02*
Y46120D01*
G01X101129Y45840D02*
Y44810D01*
G01X101019Y44710D02*
Y45930D01*
G01X102019Y45000D02*
Y44380D01*
G01X102219Y44190D02*
Y44820D01*
G01X102429Y44630D02*
Y44010D01*
G01X103759Y44620D02*
Y47110D01*
G01Y44570D02*
Y44620D01*
G01X103519Y47120D02*
Y47760D01*
G01X103329Y47570D02*
Y46930D01*
G01X103829Y48050D02*
Y44530D01*
G01X104789Y44570D02*
Y44620D01*
G01X104749Y44530D02*
X104789Y44570D01*
G01X103799Y44530D02*
X104749D01*
G01X104629D02*
Y47790D01*
G01X104429Y47820D02*
Y44530D01*
G01X104219D02*
Y48440D01*
G01X104019Y48240D02*
Y44530D01*
G01X108679Y44590D02*
X109019D01*
G01X108629Y44630D02*
X108679Y44590D01*
G01X109019Y44580D02*
Y47210D01*
G01X108629Y47080D02*
Y44630D01*
G01X108679Y47130D02*
X108629Y47080D01*
G01X108959Y47130D02*
X108679D01*
G01X108719Y44590D02*
Y47130D01*
G01X108829D02*
Y44590D01*
G01X108929D02*
Y47130D01*
G01X109239Y46680D02*
X109199D01*
G01X109339Y46580D02*
X109239Y46680D01*
G01X109339Y45140D02*
Y46580D01*
G01X109239Y45040D02*
X109339Y45140D01*
G01X109199Y45040D02*
X109239D01*
G01X109089Y45140D02*
X109199Y45040D01*
G01X109089Y46580D02*
Y45140D01*
G01X109199Y46680D02*
X109089Y46580D01*
G01X109219Y46680D02*
Y48650D01*
G01X109329Y48360D02*
Y46590D01*
G01X109759Y44590D02*
X109729D01*
G01X109799Y44630D02*
X109759Y44590D01*
G01X109799Y47080D02*
Y44630D01*
G01X109759Y47130D02*
X109799Y47080D01*
G01X109659Y47130D02*
X109759D01*
G01X109719Y44580D02*
Y47130D01*
G01X109219Y45040D02*
Y42210D01*
G01X109429Y42230D02*
Y47990D01*
G01X109559Y47210D02*
X109659Y47130D01*
G01X109559Y47260D02*
Y47210D01*
G01X109469Y47820D02*
X109559Y47260D01*
G01X109429Y48000D02*
X109469Y47820D01*
G01X109519Y47440D02*
Y43570D01*
G01X108989Y47640D02*
X108899Y48050D01*
G01X109039Y47350D02*
X108989Y47640D01*
G01X109039Y47320D02*
Y47350D01*
G01X109059Y47240D02*
X109039Y47320D01*
G01X108959Y47130D02*
X109059Y47240D01*
G01X109019Y47430D02*
Y49020D01*
G01X104789Y47740D02*
Y44620D01*
G01X104719Y44530D02*
Y47790D01*
G01X104749Y47780D02*
X104789Y47740D01*
G01X104399Y47960D02*
X104599Y48160D01*
G01X104369Y47850D02*
X104399Y47960D01*
G01X104469Y47790D02*
X104369Y47850D01*
G01X104649Y47790D02*
X104469D01*
G01X104659D02*
X104649D01*
G01X104749Y47780D02*
X104659Y47790D01*
G01X104429Y47990D02*
Y48630D01*
G01X104519Y47790D02*
Y44530D01*
G01X103019Y46640D02*
Y47280D01*
G01X103699Y47200D02*
X103759Y47110D01*
G01X103589Y47180D02*
X103699Y47200D01*
G01X103219Y46830D02*
X103589Y47180D01*
G01X103219Y47470D02*
Y46830D01*
G01X103719Y47160D02*
Y47950D01*
G01X103629Y47860D02*
Y47190D01*
G01X103429Y47030D02*
Y47660D01*
G01X99629Y47230D02*
Y46600D01*
G01X99429Y46790D02*
Y47420D01*
G01X99219Y47600D02*
Y46970D01*
G01X99019Y47160D02*
Y47790D01*
G01X98929Y47880D02*
Y47250D01*
G01X98829Y47340D02*
Y47980D01*
G01X98719Y48070D02*
Y47440D01*
G01X98629Y47530D02*
Y48160D01*
G01X98429Y48350D02*
Y47720D01*
G01X98219Y47900D02*
Y49040D01*
G01X98129Y49030D02*
Y48000D01*
G01X95999Y47140D02*
X95819Y47100D01*
G01X96009Y47140D02*
X95999D01*
G01X96319Y47250D02*
X96009Y47140D01*
G01X96329Y47260D02*
X96319Y47250D01*
G01X96639Y47470D02*
X96329Y47260D01*
G01X96649Y47480D02*
X96639Y47470D01*
G01X96869Y47720D02*
X96649Y47480D01*
G01X96869Y47730D02*
Y47720D01*
G01X96949Y47850D02*
X96869Y47730D01*
G01X96959Y47860D02*
X96949Y47850D01*
G01X96989Y47920D02*
X96959Y47860D01*
G01X97059Y48080D02*
X96989Y47920D01*
G01X95719Y47090D02*
Y47850D01*
G01X95329Y47890D02*
Y42340D01*
G01X95349Y47880D02*
X95329Y47890D01*
G01X95609Y47830D02*
X95349Y47880D01*
G01X95619Y47830D02*
X95609D01*
G01X95639D02*
X95619D01*
G01X95019Y42380D02*
Y48120D01*
G01X95089Y48040D02*
X95179Y47980D01*
G01X95079Y48050D02*
X95089Y48040D01*
G01X95069Y48060D02*
X95079Y48050D01*
G01X95319Y47900D02*
X95329Y47890D01*
G01X95189Y47980D02*
X95319Y47900D01*
G01X95519Y47850D02*
Y47090D01*
G01X95929Y47120D02*
Y47890D01*
G01X95899Y47880D02*
X95639Y47830D01*
G01X95919Y47890D02*
X95899Y47880D01*
G01X95649Y48110D02*
X95669Y48120D01*
G01X96179Y48060D02*
X96339Y48280D01*
G01X96169Y48050D02*
X96179Y48060D01*
G01X96149Y48040D02*
X96169Y48050D01*
G01X95939Y47900D02*
X96149Y48040D01*
G01X95919Y47890D02*
X95939Y47900D01*
G01X96219Y48120D02*
Y47220D01*
G01X96129Y47180D02*
Y48020D01*
G01X96019Y47950D02*
Y47140D01*
G01X96429Y47320D02*
Y48580D01*
G01X97019Y47990D02*
Y49660D01*
G01X96929Y49750D02*
Y47810D01*
G01X96719Y47570D02*
Y49940D01*
G01X96519Y50120D02*
Y47400D01*
G01X95129Y47980D02*
Y48020D01*
G01X95069Y48060D02*
X94909Y48280D01*
G01X94329Y47850D02*
Y49400D01*
G01X94429Y49560D02*
Y47670D01*
G01X94859Y47230D02*
Y43630D01*
G01X94829Y47310D02*
X94859Y47230D01*
G01X94819Y47320D02*
X94829Y47310D01*
G01X94809Y47320D02*
X94819D01*
G01X94739Y47360D02*
X94809Y47320D01*
G01X94739Y47370D02*
Y47360D01*
G01X94729Y47380D02*
X94739Y47370D01*
G01X94629Y47450D02*
X94729Y47380D01*
G01X94619Y47460D02*
X94629Y47450D01*
G01X94399Y47690D02*
X94619Y47460D01*
G01X94629D02*
Y49800D01*
G01X94389Y47710D02*
X94399Y47690D01*
G01X94089Y48510D02*
X94099Y48850D01*
G01X94089Y48500D02*
Y48510D01*
G01Y48490D02*
Y48500D01*
G01X94109Y48330D02*
X94089Y48490D01*
G01X94109Y48310D02*
Y48330D01*
G01X94389Y47710D02*
X94109Y48310D01*
G01X94129Y48960D02*
Y48290D01*
G01X94899D02*
X94909Y48280D01*
G01X94899Y48310D02*
Y48290D01*
G01X94839Y48480D02*
X94899Y48310D01*
G01X94829Y48700D02*
Y48720D01*
G01Y48570D02*
Y48700D01*
G01X94839Y48500D02*
X94829Y48570D01*
G01X94839Y48480D02*
Y48500D01*
G01X95459Y48140D02*
X95649Y48110D01*
G01X95429Y48150D02*
X95459Y48140D01*
G01X95209Y48320D02*
X95429Y48150D01*
G01X95199Y48340D02*
X95209Y48320D01*
G01X95119Y48510D02*
X95199Y48340D01*
G01X95119Y48520D02*
Y48510D01*
G01X95109Y48560D02*
X95119Y48520D01*
G01X95109Y48620D02*
Y48560D01*
G01Y48640D02*
Y48620D01*
G01X96139Y48670D02*
Y48680D01*
G01Y48580D02*
Y48670D01*
G01X96129Y48560D02*
X96139Y48580D01*
G01X95969Y48250D02*
X96129Y48560D01*
G01X95949Y48230D02*
X95969Y48250D01*
G01X95669Y48120D02*
X95949Y48230D01*
G01X96349Y48290D02*
X96339Y48280D01*
G01X96349Y48310D02*
Y48290D01*
G01X96409Y48480D02*
X96349Y48310D01*
G01X96409Y48500D02*
Y48480D01*
G01X96419Y48570D02*
X96409Y48500D01*
G01X96429Y48590D02*
X96419Y48570D01*
G01X96429Y48650D02*
Y48590D01*
G01X96419Y48680D02*
X96429Y48650D01*
G01X96329Y48260D02*
Y47260D01*
G01X95809Y48170D02*
Y49110D01*
G01X95609Y49130D02*
Y48120D01*
G01X95409Y48170D02*
Y49080D01*
G01X95209Y48900D02*
Y48330D01*
G01X95109Y48640D02*
X95129Y48770D01*
G01X95999Y48970D02*
Y48320D01*
G01X96419Y48720D02*
X96369Y48920D01*
G01X96419Y48680D02*
Y48720D01*
G01X97089Y48170D02*
X97059Y48080D01*
G01X97099Y48180D02*
X97089Y48170D01*
G01X97129Y48320D02*
X97099Y48180D01*
G01X97149Y48400D02*
X97129Y48320D01*
G01X97929Y48180D02*
X99109Y47080D01*
G01X97649Y48440D02*
X97929Y48180D01*
G01X97599Y48470D02*
X97649Y48440D01*
G01X97449Y48500D02*
X97599Y48470D01*
G01X97429Y48510D02*
X97449Y48500D01*
G01X97409Y48510D02*
X97429D01*
G01X97239Y48490D02*
X97409Y48510D01*
G01X97229Y48490D02*
X97239D01*
G01X97149Y48400D02*
X97229Y48490D01*
G01X98519Y47620D02*
Y48260D01*
G01X98419Y48580D02*
X104649Y49090D01*
G01X98339Y48520D02*
X98419Y48580D01*
G01X98359Y48410D02*
X98339Y48520D01*
G01X104629Y48180D02*
X104599Y48160D01*
G01X104629Y48820D02*
Y48180D01*
G01D02*
X105469Y48990D01*
G01X105019Y48570D02*
Y50830D01*
G01X104829D02*
Y48380D01*
G01X104519Y48080D02*
Y48720D01*
G01X104329Y48530D02*
Y44530D01*
G01X104129D02*
Y48340D01*
G01X103929Y48140D02*
Y44530D01*
G01X100429Y48750D02*
Y49210D01*
G01X100219Y49200D02*
Y48730D01*
G01X100019Y48710D02*
Y49180D01*
G01X99829Y49170D02*
Y48700D01*
G01X99629Y48680D02*
Y49150D01*
G01X99429Y49140D02*
Y48670D01*
G01X99219Y48650D02*
Y49120D01*
G01X99019Y49100D02*
Y48640D01*
G01X98829Y48620D02*
Y49080D01*
G01X98629Y49070D02*
Y48600D01*
G01X98429Y48580D02*
Y49050D01*
G01X97929Y49010D02*
Y48180D01*
G01X97719Y48370D02*
Y49010D01*
G01X97519Y49190D02*
Y48490D01*
G01X97329Y48500D02*
Y49380D01*
G01X108819Y48330D02*
X108899Y48050D01*
G01X108809Y48340D02*
X108819Y48330D01*
G01X108779Y48450D02*
X108809Y48340D01*
G01X108769Y48450D02*
X108779D01*
G01X108729Y48560D02*
X108769Y48450D01*
G01X108719Y48570D02*
X108729Y48560D01*
G01X108719Y49430D02*
Y48570D01*
G01X108829Y48290D02*
Y49320D01*
G01X109389Y48120D02*
X109429Y48000D01*
G01X109369Y48230D02*
X109389Y48120D01*
G01X109289Y48470D02*
X109369Y48230D01*
G01X109249Y48580D02*
X109289Y48470D01*
G01X109229Y48640D02*
X109249Y48580D01*
G01X108929Y47930D02*
Y49180D01*
G01X109129Y48860D02*
Y46610D01*
G01X108169Y49180D02*
X108119Y49090D01*
G01X108269Y49170D02*
X108169Y49180D01*
G01X108379Y49100D02*
X108269Y49170D01*
G01X108399Y49080D02*
X108379Y49100D01*
G01X108619Y48780D02*
X108399Y49080D01*
G01X108629Y48770D02*
X108619Y48780D01*
G01X108629Y48760D02*
Y48770D01*
G01X108719Y48570D02*
X108629Y48760D01*
G01X108129Y49100D02*
Y50820D01*
G01X108329Y50800D02*
Y49140D01*
G01X108519Y48910D02*
Y50720D01*
G01X106519Y50830D02*
Y49050D01*
G01X105499Y49020D02*
X105469Y48990D01*
G01X105559Y49050D02*
X105499Y49020D01*
G01X106579Y49050D02*
X105559D01*
G01X105429Y48950D02*
Y49620D01*
G01X105629Y49790D02*
Y49050D01*
G01X105829D02*
Y49980D01*
G01X106019Y50170D02*
Y49050D01*
G01X106129D02*
Y50830D01*
G01X106329D02*
Y49050D01*
G01X106659Y49160D02*
X106759Y49260D01*
G01X106659Y49090D02*
Y49160D01*
G01X106619Y49050D02*
X106659Y49090D01*
G01X106579Y49050D02*
X106619D01*
G01X105219Y48760D02*
Y50830D01*
G01X104519Y49550D02*
Y49080D01*
G01X104729Y48920D02*
X101399Y45710D01*
G01X104749Y49030D02*
X104729Y48920D01*
G01X104649Y49090D02*
X104749Y49030D01*
G01X101219Y48810D02*
Y49280D01*
G01X101329Y49290D02*
Y48820D01*
G01X101519Y48840D02*
Y49310D01*
G01X101719Y49320D02*
Y48860D01*
G01X101929Y48870D02*
Y49340D01*
G01X102129Y49350D02*
Y48890D01*
G01X102329Y48900D02*
Y49370D01*
G01X102519Y49390D02*
Y48920D01*
G01X102719Y48940D02*
Y49400D01*
G01X102929Y49420D02*
Y48950D01*
G01X103129Y48970D02*
Y49440D01*
G01X103329Y49450D02*
Y48990D01*
G01X103519Y49000D02*
Y49470D01*
G01X103719Y49480D02*
Y49020D01*
G01X103929Y49030D02*
Y49500D01*
G01X104129Y49520D02*
Y49050D01*
G01X104329Y49070D02*
Y49530D01*
G01X104719Y48920D02*
Y48280D01*
G01X101019Y48800D02*
Y49270D01*
G01X100829Y49250D02*
Y48780D01*
G01X100629Y48770D02*
Y49230D01*
G01X100519Y49220D02*
Y48760D01*
G01X100329Y48740D02*
Y49210D01*
G01X100129Y49190D02*
Y48720D01*
G01X99929Y48710D02*
Y49180D01*
G01X99719Y49160D02*
Y48690D01*
G01X99519Y48680D02*
Y49140D01*
G01X99329Y49130D02*
Y48660D01*
G01X99129Y48640D02*
Y49110D01*
G01X98929Y49090D02*
Y48630D01*
G01X98719Y48610D02*
Y49080D01*
G01X98519Y49060D02*
Y48590D01*
G01X98329Y49050D02*
Y47810D01*
G01X98019Y48090D02*
Y49020D01*
G01X97829Y49010D02*
Y48280D01*
G01X97629Y48450D02*
Y49090D01*
G01X97689Y49030D02*
X96669Y49990D01*
G01X96329Y50310D02*
Y48980D01*
G01X96349Y48960D02*
X96369Y48920D01*
G01X96349Y48960D02*
X96089Y49270D01*
G01X95909Y49040D02*
Y48210D01*
G01X95709Y48130D02*
Y49120D01*
G01X96039Y48930D02*
X96139Y48680D01*
G01X96029Y48950D02*
X96039Y48930D01*
G01X95829Y49100D02*
X96029Y48950D01*
G01X95799Y49110D02*
X95829Y49100D01*
G01X96109Y48770D02*
Y48500D01*
G01X95129Y48790D02*
Y48770D01*
G01X95269Y49010D02*
X95129Y48790D01*
G01X95289Y49020D02*
X95269Y49010D01*
G01X95519Y49130D02*
X95289Y49020D01*
G01X95539Y49140D02*
X95519Y49130D01*
G01X95799Y49110D02*
X95539Y49140D01*
G01X94929Y48980D02*
Y50000D01*
G01X94099Y48860D02*
Y48850D01*
G01X94169Y49150D02*
X94099Y48860D01*
G01X94179Y49160D02*
X94169Y49150D01*
G01X94489Y49670D02*
X94179Y49160D01*
G01X94879Y48920D02*
X94899Y48960D01*
G01X94829Y48720D02*
X94879Y48920D01*
G01X95309Y49030D02*
Y48250D01*
G01X95499Y48130D02*
Y49130D01*
G01X97709Y49020D02*
X97779Y49000D01*
G01X97699Y49030D02*
X97709Y49020D01*
G01X97689Y49030D02*
X97699D01*
G01X109169Y48790D02*
X109229Y48640D01*
G01X109159Y48800D02*
X109169Y48790D01*
G01X108879Y50050D02*
X108889Y50110D01*
G01X108879Y50040D02*
Y50050D01*
G01X108849Y49930D02*
X108879Y50040D01*
G01X108849Y49920D02*
Y49930D01*
G01X108799Y49790D02*
X108849Y49920D01*
G01X108789Y49790D02*
X108799D01*
G01X108759Y49730D02*
X108789Y49790D01*
G01X108739Y49710D02*
X108759Y49730D01*
G01X108689Y49650D02*
X108739Y49710D01*
G01X108669Y49630D02*
X108689Y49650D01*
G01X108669Y49490D02*
Y49630D01*
G01X108839Y49310D02*
X108669Y49490D01*
G01X108849Y49300D02*
X108839Y49310D01*
G01X109159Y48800D02*
X108849Y49300D01*
G01X108829Y49860D02*
Y50380D01*
G01X107519Y50430D02*
Y49270D01*
G01X107469Y49320D02*
X106759Y49260D01*
G01X106719Y49230D02*
Y49780D01*
G01X107449Y50070D02*
X107439Y50100D01*
G01X107459Y49990D02*
X107449Y50070D01*
G01X107479Y49920D02*
X107459Y49990D01*
G01X107479Y49910D02*
Y49920D01*
G01X107389Y49780D02*
X107479Y49910D01*
G01X106779Y49730D02*
X107389Y49780D01*
G01X106669Y49830D02*
X106779Y49730D01*
G01X107429Y49830D02*
Y49320D01*
G01X107579Y49220D02*
Y41870D01*
G01X107469Y49320D02*
X107579Y49220D01*
G01X105329Y48860D02*
Y49680D01*
G01X105479Y49650D02*
X106059Y50200D01*
G01X105429Y49620D02*
X105479Y49650D01*
G01X105389Y49620D02*
X105429D01*
G01X105279Y49720D02*
X105389Y49620D01*
G01X105929Y50080D02*
Y49050D01*
G01X105719D02*
Y49880D01*
G01X105519Y49690D02*
Y49030D01*
G01X104719Y49050D02*
Y49580D01*
G01X104709Y49570D02*
X97779Y49000D01*
G01X97429Y49280D02*
Y48510D01*
G01X97219Y48480D02*
Y49470D01*
G01X97129Y49560D02*
Y48290D01*
G01X96829Y47680D02*
Y49840D01*
G01X96629Y50030D02*
Y47460D01*
G01X94829Y47310D02*
Y49940D01*
G01X94579Y49760D02*
X94489Y49670D01*
G01X94649Y49820D02*
X94579Y49760D01*
G01X94839Y49950D02*
X94649Y49820D01*
G01X94519Y49710D02*
Y47560D01*
G01X94719Y47380D02*
Y49870D01*
G01X95089Y50070D02*
X95259Y50130D01*
G01X94989Y50030D02*
X95089Y50070D01*
G01X94979Y50030D02*
X94989D01*
G01X94849Y49960D02*
X94979Y50030D01*
G01X94839Y49950D02*
X94849Y49960D01*
G01X95219Y50120D02*
Y49305D01*
G01Y49310D02*
Y49370D01*
G01X95159Y49270D02*
X94899Y48960D01*
G01X95209Y49300D02*
X95159Y49270D01*
G01X95019Y49100D02*
Y50050D01*
G01X95129Y50080D02*
Y49290D01*
G01Y50050D02*
Y50080D01*
G01X96039Y49300D02*
X96089Y49270D01*
G01X95649Y49420D02*
X96039Y49300D01*
G01X95589Y49420D02*
X95649D01*
G01X95209Y49300D02*
X95589Y49420D01*
G01X96129Y49230D02*
Y50490D01*
G01X95929Y50680D02*
Y49340D01*
G01X95719Y49400D02*
Y50860D01*
G01X95519Y50160D02*
Y49400D01*
G01X95329Y49340D02*
Y50140D01*
G01X94219Y49230D02*
Y48070D01*
G01X100719Y48770D02*
Y49240D01*
G01X100929Y49260D02*
Y48790D01*
G01X101129Y48810D02*
Y49270D01*
G01X101429Y49300D02*
Y48830D01*
G01X101629Y48840D02*
Y49310D01*
G01X101829Y49330D02*
Y48860D01*
G01X102019Y48880D02*
Y49340D01*
G01X102219Y49360D02*
Y48900D01*
G01X102429Y48910D02*
Y49380D01*
G01X102629Y49400D02*
Y48930D01*
G01X102829Y48940D02*
Y49410D01*
G01X103019Y49430D02*
Y48960D01*
G01X103219Y48980D02*
Y49440D01*
G01X103429Y49460D02*
Y48990D01*
G01X103629Y49010D02*
Y49470D01*
G01X103829Y49490D02*
Y49030D01*
G01X104019Y49040D02*
Y49510D01*
G01X104219Y49530D02*
Y49060D01*
G01X104429Y49070D02*
Y49540D01*
G01X104629Y49560D02*
Y49090D01*
G01X104709Y49570D02*
X104799Y49660D01*
G01X106659Y49990D02*
Y50110D01*
G01X106669Y49830D02*
X106659Y49990D01*
G01X106829Y49740D02*
Y49270D01*
G01X106929Y49280D02*
Y49750D01*
G01X107019D02*
Y49290D01*
G01X107129D02*
Y49760D01*
G01X107219Y49770D02*
Y49300D01*
G01X107329Y49310D02*
Y49780D01*
G01X108889Y50180D02*
Y50110D01*
G01X108879Y50190D02*
X108889Y50180D01*
G01X108809Y50450D02*
X108879Y50190D01*
G01X108799Y50460D02*
X108809Y50450D01*
G01X108629Y50660D02*
X108799Y50460D01*
G01X108619Y50670D02*
X108629Y50660D01*
G01X108389Y50790D02*
X108619Y50670D01*
G01X108369Y50800D02*
X108389Y50790D01*
G01X108089Y50820D02*
X108369Y50800D01*
G01X108079Y50820D02*
X108089D01*
G01X107819Y50740D02*
X108079Y50820D01*
G01X107809Y50730D02*
X107819Y50740D01*
G01X107609Y50570D02*
X107809Y50730D01*
G01X107589Y50560D02*
X107609Y50570D01*
G01X107469Y50330D02*
X107589Y50560D01*
G01X107469Y50310D02*
Y50330D01*
G01X107449Y50190D02*
X107469Y50310D01*
G01X107449Y50180D02*
Y50190D01*
G01X107439Y50120D02*
X107449Y50180D01*
G01X107439Y50100D02*
Y50120D01*
G01X108719Y49690D02*
Y50550D01*
G01X108629Y50660D02*
Y48770D01*
G01X108429Y49050D02*
Y50770D01*
G01X108219Y50810D02*
Y49180D01*
G01X107719Y50670D02*
Y40560D01*
G01X107929D02*
Y50770D01*
G01X107629Y51080D02*
Y51710D01*
G01X107719Y51810D02*
Y51180D01*
G01X107829Y51270D02*
Y51910D01*
G01X107929Y52000D02*
Y51370D01*
G01X108019Y51470D02*
Y52100D01*
G01X108129Y52190D02*
Y51570D01*
G01X108219Y51660D02*
Y52290D01*
G01X108329Y52390D02*
Y51760D01*
G01X108429Y51860D02*
Y52490D01*
G01X108629Y52680D02*
Y52050D01*
G01X108829Y52240D02*
Y52870D01*
G01X107519Y51620D02*
Y50990D01*
G01X107429Y50890D02*
Y51520D01*
G01X107329Y51420D02*
Y50790D01*
G01X107219Y50690D02*
Y51330D01*
G01X107129Y51230D02*
Y50600D01*
G01X107019Y50500D02*
Y51140D01*
G01X106929Y51040D02*
Y50410D01*
G01X106829Y50310D02*
Y50940D01*
G01X104799Y50790D02*
Y49660D01*
G01X104819Y50830D02*
X104799Y50790D01*
G01X104829Y50830D02*
X104819D01*
G01X106649D02*
X104829D01*
G01X106659D02*
X106649D01*
G01X106739Y50860D02*
X106659Y50830D01*
G01X106079Y50310D02*
X106059Y50200D01*
G01X105979Y50370D02*
X106079Y50310D01*
G01X105379Y50370D02*
X105979D01*
G01X105279Y50270D02*
X105379Y50370D01*
G01X105279Y49720D02*
Y50270D01*
G01X106019Y50340D02*
Y50830D01*
G01X105929D02*
Y50370D01*
G01X105829D02*
Y50830D01*
G01X105719D02*
Y50370D01*
G01X105629D02*
Y50830D01*
G01X105519D02*
Y50370D01*
G01X105429D02*
Y50830D01*
G01X105329D02*
Y50320D01*
G01X105129Y50830D02*
Y48660D01*
G01X104929Y48470D02*
Y50830D01*
G01X106219D02*
Y49050D01*
G01X106429D02*
Y50830D01*
G01X106629D02*
Y49050D01*
G01X106659Y50110D02*
X106689Y50180D01*
G01X106719Y50210D02*
Y50850D01*
G01X96429Y50210D02*
Y48660D01*
G01X96219Y49100D02*
Y50400D01*
G01X96019Y50580D02*
Y49310D01*
G01X95829Y49360D02*
Y50770D01*
G01X95629Y50960D02*
Y50270D01*
G01X95279Y50130D02*
X95259D01*
G01X95549Y50170D02*
X95279Y50130D01*
G01X95629Y50230D02*
X95549Y50170D01*
G01X95429Y50150D02*
Y49370D01*
G01X95629Y50230D02*
X95609Y50340D01*
G01X95629Y49420D02*
Y50230D01*
G01X95519Y50420D02*
Y51050D01*
G01X95429Y51140D02*
Y50510D01*
G01X95329Y50600D02*
Y51240D01*
G01X95219Y51290D02*
Y51330D01*
G01Y51340D02*
Y50700D01*
G01X95129Y50790D02*
Y51425D01*
G01Y51420D02*
Y51370D01*
G01X95019Y51525D02*
Y50880D01*
G01X94929Y50970D02*
Y51610D01*
G01X94829Y51700D02*
Y51065D01*
G01X94719Y51165D02*
Y51800D01*
G01X94629Y51890D02*
Y51250D01*
G01X94519Y51355D02*
Y51980D01*
G01X94429Y52080D02*
Y51440D01*
G01X94329Y51530D02*
Y52170D01*
G01X94219Y52260D02*
Y51620D01*
G01X94129Y51710D02*
Y52360D01*
G01X93929Y52540D02*
Y51900D01*
G01X94019Y51810D02*
Y52450D01*
G01X93829Y52630D02*
Y51990D01*
G01X93719Y52090D02*
Y52730D01*
G01X93629Y52820D02*
Y52180D01*
G01X93519Y52270D02*
Y52910D01*
G01X93429Y53010D02*
Y52360D01*
G01X93329Y52460D02*
Y53100D01*
G01X93219Y53190D02*
Y52550D01*
G01X93129Y52640D02*
Y53290D01*
G01X93019Y53380D02*
Y52740D01*
G01X92929Y52830D02*
Y53470D01*
G01X92719Y53660D02*
Y53020D01*
G01X92519Y53200D02*
Y53810D01*
G01X92579Y53800D02*
X96669Y49990D01*
G01X92239Y53470D02*
X92219Y53490D01*
G01X95609Y50340D02*
X92239Y53470D01*
G01X92329Y53390D02*
Y53610D01*
G01X92559Y36530D02*
X98169Y41950D01*
G01X92529Y36500D02*
X92559Y36530D01*
G01X92509Y36510D02*
X92529Y36500D01*
G01X92239Y36820D02*
X92509Y36510D01*
G01X92229Y36850D02*
X92239Y36820D01*
G01Y36870D02*
X92229Y36850D01*
G01X97539Y41990D02*
X92239Y36870D01*
G01X92329Y36950D02*
Y36720D01*
G01X92429Y36600D02*
Y37050D01*
G01X92519Y37150D02*
Y36500D01*
G01X92629Y36590D02*
Y37250D01*
G01X92719Y37340D02*
Y36690D01*
G01X92829Y36780D02*
Y37440D01*
G01X92929Y37530D02*
Y36880D01*
G01X93019Y36970D02*
Y37630D01*
G01X93129Y37730D02*
Y37070D01*
G01X93219Y37170D02*
Y37820D01*
G01X93329Y37920D02*
Y37270D01*
G01X93429Y37360D02*
Y38020D01*
G01X93519Y38110D02*
Y37460D01*
G01X93629Y37560D02*
Y38210D01*
G01X93719Y38310D02*
Y37650D01*
G01X93829Y37750D02*
Y38400D01*
G01X106689Y50180D02*
X111429Y54760D01*
G01X110819Y54790D02*
X106739Y50860D01*
G01X108519Y51950D02*
Y52580D01*
G01X108719Y52770D02*
Y52140D01*
G01X108929Y52340D02*
Y52970D01*
G01X109019Y53070D02*
Y52440D01*
G01X109129Y52530D02*
Y53160D01*
G01X109219Y53260D02*
Y52630D01*
G01X109329Y52730D02*
Y53350D01*
G01X109429Y53450D02*
Y52820D01*
G01X109629Y53010D02*
Y53640D01*
G01X109829Y53840D02*
Y53210D01*
G01X110019Y53400D02*
Y54030D01*
G01X109929Y53930D02*
Y53310D01*
G01X110129Y53500D02*
Y54120D01*
G01X110219Y54220D02*
Y53590D01*
G01X110329Y53690D02*
Y54320D01*
G01X110429Y54420D02*
Y53790D01*
G01X110519Y53880D02*
Y54510D01*
G01X110629Y54610D02*
Y53980D01*
G01X110719Y54080D02*
Y54700D01*
G01X110929Y54810D02*
Y54270D01*
G01X110849Y54800D02*
X110929Y54810D01*
G01X110819Y54790D02*
X110849Y54800D01*
G01X110829Y54180D02*
Y54790D01*
G01X111419Y54810D02*
X111429Y54760D01*
G01X110929Y54810D02*
X111419D01*
G01X111429Y54750D02*
Y54790D01*
G01X111329Y54810D02*
Y54660D01*
G01X111219Y54560D02*
Y54810D01*
G01X111129D02*
Y54460D01*
G01X111019Y54370D02*
Y54810D01*
G01X109719Y53740D02*
Y53110D01*
G01X109519Y52920D02*
Y53550D01*
G01X92829Y53570D02*
Y52920D01*
G01X92629Y53110D02*
Y53750D01*
G01X92239Y53520D02*
X92219Y53490D01*
G01X92529Y53810D02*
X92239Y53520D01*
G01X92549Y53820D02*
X92529Y53810D01*
G01X92559D02*
X92549Y53820D01*
G01X92579Y53800D02*
X92559Y53810D01*
G01X92429Y53290D02*
Y53710D01*
G54D14*
G01X-322688Y-405500D02*
X-321814Y-404625D01*
X-321159Y-403167D01*
X-320722Y-401124D01*
X-321159Y-399375D01*
X-322032Y-398208D01*
X-323561Y-397333D01*
X-329456D01*
Y-414833D01*
X-322251D01*
X-320722Y-413667D01*
X-319849Y-411916D01*
X-319412Y-409875D01*
X-319849Y-407833D01*
X-321159Y-406083D01*
X-322688Y-405500D01*
X-329456D01*
G01X-309991Y-414833D02*
Y-403167D01*
G01Y-405500D02*
X-308899Y-404333D01*
X-307807Y-403458D01*
X-306279Y-403167D01*
X-305188Y-403458D01*
X-303877Y-404333D01*
G01X-294019Y-420083D02*
X-292709Y-420666D01*
X-290962Y-420083D01*
X-289871Y-418917D01*
X-288997Y-417458D01*
X-287688Y-412792D01*
X-284849Y-403167D01*
G01X-291836D02*
X-287688Y-412792D01*
G01X-268441Y-404625D02*
X-269969Y-403458D01*
X-271279Y-403167D01*
X-273026Y-403750D01*
X-274336Y-404916D01*
X-275209Y-406958D01*
X-275428Y-409000D01*
X-275209Y-411042D01*
X-274336Y-412792D01*
X-273026Y-414250D01*
X-271279Y-414833D01*
X-269751Y-414250D01*
X-268441Y-413083D01*
G01X-257709Y-406958D02*
X-250722D01*
X-251377Y-404916D01*
X-252469Y-403750D01*
X-253997Y-403167D01*
X-255526Y-403458D01*
X-256836Y-404333D01*
X-257709Y-406375D01*
X-258146Y-408125D01*
Y-409875D01*
X-257709Y-411625D01*
X-256617Y-413375D01*
X-255307Y-414541D01*
X-253779Y-414833D01*
X-252251Y-414250D01*
X-250722Y-412500D01*
G01X-214631Y-398792D02*
X-215941Y-397916D01*
X-217469Y-397333D01*
X-219216D01*
X-221181Y-398208D01*
X-222709Y-399666D01*
X-223801Y-401417D01*
X-224674Y-404333D01*
X-224893Y-406958D01*
X-224456Y-409583D01*
X-223801Y-411333D01*
X-222491Y-413083D01*
X-220962Y-414250D01*
X-219434Y-414833D01*
X-217906D01*
X-216377Y-414250D01*
X-215067Y-413375D01*
X-213975Y-412209D01*
G01X-198004Y-414833D02*
Y-403167D01*
G01Y-405208D02*
X-198877Y-404042D01*
X-200188Y-403458D01*
X-201716Y-403167D01*
X-203244Y-403750D01*
X-204554Y-404916D01*
X-205428Y-406666D01*
X-205864Y-409000D01*
X-205428Y-411333D01*
X-204554Y-413083D01*
X-203244Y-414250D01*
X-201716Y-414833D01*
X-200188Y-414541D01*
X-198877Y-413667D01*
X-198004Y-412500D01*
G01X-188146Y-414833D02*
Y-403167D01*
G01Y-406083D02*
X-187272Y-404625D01*
X-185962Y-403458D01*
X-184216Y-403167D01*
X-182688Y-403458D01*
X-181377Y-404625D01*
X-180722Y-406666D01*
Y-414833D01*
G01X-171519Y-420083D02*
X-170209Y-420666D01*
X-168462Y-420083D01*
X-167371Y-418917D01*
X-166497Y-417458D01*
X-165188Y-412792D01*
X-162349Y-403167D01*
G01X-169336D02*
X-165188Y-412792D01*
G01X-149434Y-414833D02*
X-150744Y-414541D01*
X-152054Y-413375D01*
X-152928Y-411333D01*
X-153364Y-409000D01*
X-152928Y-406666D01*
X-152054Y-404625D01*
X-150744Y-403458D01*
X-149434Y-403167D01*
X-148124Y-403458D01*
X-146814Y-404625D01*
X-145941Y-406666D01*
X-145722Y-409000D01*
X-145941Y-411333D01*
X-146814Y-413375D01*
X-148124Y-414541D01*
X-149434Y-414833D01*
G01X-135646D02*
Y-403167D01*
G01Y-406083D02*
X-134772Y-404625D01*
X-133462Y-403458D01*
X-131716Y-403167D01*
X-130188Y-403458D01*
X-128877Y-404625D01*
X-128222Y-406666D01*
Y-414833D01*
G01X-101082D02*
Y-397333D01*
X-92786D01*
G01X-95842Y-405791D02*
X-101082D01*
G01X-82491Y-414833D02*
Y-403167D01*
G01Y-405500D02*
X-81399Y-404333D01*
X-80307Y-403458D01*
X-78779Y-403167D01*
X-77688Y-403458D01*
X-76377Y-404333D01*
G01X-61934Y-414833D02*
X-63244Y-414541D01*
X-64554Y-413375D01*
X-65428Y-411333D01*
X-65864Y-409000D01*
X-65428Y-406666D01*
X-64554Y-404625D01*
X-63244Y-403458D01*
X-61934Y-403167D01*
X-60624Y-403458D01*
X-59314Y-404625D01*
X-58441Y-406666D01*
X-58222Y-409000D01*
X-58441Y-411333D01*
X-59314Y-413375D01*
X-60624Y-414541D01*
X-61934Y-414833D01*
G01X-48146D02*
Y-403167D01*
G01Y-406083D02*
X-47272Y-404625D01*
X-45962Y-403458D01*
X-44216Y-403167D01*
X-42688Y-403458D01*
X-41377Y-404625D01*
X-40722Y-406666D01*
Y-414833D01*
G01X-26934Y-397333D02*
Y-414833D01*
G01X-29991Y-403167D02*
X-23877D01*
G01X3699Y-414833D02*
Y-397333D01*
X8939D01*
X10686Y-398208D01*
X11996Y-400250D01*
X12433Y-402583D01*
X11996Y-404916D01*
X10904Y-406666D01*
X8939Y-407542D01*
X3699D01*
G01X29496Y-414833D02*
Y-403167D01*
G01Y-405208D02*
X28623Y-404042D01*
X27312Y-403458D01*
X25784Y-403167D01*
X24256Y-403750D01*
X22946Y-404916D01*
X22072Y-406666D01*
X21636Y-409000D01*
X22072Y-411333D01*
X22946Y-413083D01*
X24256Y-414250D01*
X25784Y-414833D01*
X27312Y-414541D01*
X28623Y-413667D01*
X29496Y-412500D01*
G01X39354Y-414833D02*
Y-403167D01*
G01Y-406083D02*
X40228Y-404625D01*
X41538Y-403458D01*
X43284Y-403167D01*
X44812Y-403458D01*
X46123Y-404625D01*
X46778Y-406666D01*
Y-414833D01*
G01X57291Y-406958D02*
X64278D01*
X63623Y-404916D01*
X62531Y-403750D01*
X61003Y-403167D01*
X59474Y-403458D01*
X58164Y-404333D01*
X57291Y-406375D01*
X56854Y-408125D01*
Y-409875D01*
X57291Y-411625D01*
X58383Y-413375D01*
X59693Y-414541D01*
X61221Y-414833D01*
X62749Y-414250D01*
X64278Y-412500D01*
G01X78066Y-414833D02*
Y-397333D01*
G01X114812Y-405500D02*
X115686Y-404625D01*
X116341Y-403167D01*
X116778Y-401124D01*
X116341Y-399375D01*
X115468Y-398208D01*
X113939Y-397333D01*
X108044D01*
Y-414833D01*
X115249D01*
X116778Y-413667D01*
X117651Y-411916D01*
X118088Y-409875D01*
X117651Y-407833D01*
X116341Y-406083D01*
X114812Y-405500D01*
X108044D01*
G01X130566Y-414833D02*
X129256Y-414541D01*
X127946Y-413375D01*
X127072Y-411333D01*
X126636Y-409000D01*
X127072Y-406666D01*
X127946Y-404625D01*
X129256Y-403458D01*
X130566Y-403167D01*
X131876Y-403458D01*
X133186Y-404625D01*
X134059Y-406666D01*
X134278Y-409000D01*
X134059Y-411333D01*
X133186Y-413375D01*
X131876Y-414541D01*
X130566Y-414833D01*
G01X151996D02*
Y-403167D01*
G01Y-405208D02*
X151123Y-404042D01*
X149812Y-403458D01*
X148284Y-403167D01*
X146756Y-403750D01*
X145446Y-404916D01*
X144572Y-406666D01*
X144136Y-409000D01*
X144572Y-411333D01*
X145446Y-413083D01*
X146756Y-414250D01*
X148284Y-414833D01*
X149812Y-414541D01*
X151123Y-413667D01*
X151996Y-412500D01*
G01X162509Y-414833D02*
Y-403167D01*
G01Y-405500D02*
X163601Y-404333D01*
X164693Y-403458D01*
X166221Y-403167D01*
X167312Y-403458D01*
X168623Y-404333D01*
G01X186996Y-397333D02*
Y-414833D01*
G01Y-412209D02*
X186123Y-413667D01*
X184812Y-414541D01*
X183284Y-414833D01*
X181538Y-414250D01*
X180228Y-412792D01*
X179354Y-411042D01*
X179136Y-409000D01*
X179354Y-406958D01*
X180228Y-405208D01*
X181538Y-403750D01*
X183284Y-403167D01*
X184812Y-403458D01*
X185904Y-404042D01*
X186996Y-405208D01*
G01X-111361Y-369833D02*
Y-352333D01*
X-105684Y-366916D01*
X-100007Y-352333D01*
Y-369833D01*
G01X-88184D02*
X-89494Y-369541D01*
X-90804Y-368375D01*
X-91678Y-366333D01*
X-92114Y-364000D01*
X-91678Y-361666D01*
X-90804Y-359625D01*
X-89494Y-358458D01*
X-88184Y-358167D01*
X-86874Y-358458D01*
X-85564Y-359625D01*
X-84691Y-361666D01*
X-84472Y-364000D01*
X-84691Y-366333D01*
X-85564Y-368375D01*
X-86874Y-369541D01*
X-88184Y-369833D01*
G01X-66754Y-352333D02*
Y-369833D01*
G01Y-367209D02*
X-67627Y-368667D01*
X-68938Y-369541D01*
X-70466Y-369833D01*
X-72212Y-369250D01*
X-73522Y-367792D01*
X-74396Y-366042D01*
X-74614Y-364000D01*
X-74396Y-361958D01*
X-73522Y-360208D01*
X-72212Y-358750D01*
X-70466Y-358167D01*
X-68938Y-358458D01*
X-67846Y-359042D01*
X-66754Y-360208D01*
G01X-56459Y-361958D02*
X-49472D01*
X-50127Y-359916D01*
X-51219Y-358750D01*
X-52747Y-358167D01*
X-54276Y-358458D01*
X-55586Y-359333D01*
X-56459Y-361375D01*
X-56896Y-363125D01*
Y-364875D01*
X-56459Y-366625D01*
X-55367Y-368375D01*
X-54057Y-369541D01*
X-52529Y-369833D01*
X-51001Y-369250D01*
X-49472Y-367500D01*
G01X-35684Y-369833D02*
Y-352333D01*
G01X244916Y-414833D02*
Y-397333D01*
X242296Y-400833D01*
G01Y-414833D02*
X247536D01*
G01X258268Y-407542D02*
X259796Y-405500D01*
X261106Y-404333D01*
X262853Y-403750D01*
X264381Y-404333D01*
X265473Y-405500D01*
X266346Y-407250D01*
X266564Y-409291D01*
X266346Y-411042D01*
X265473Y-412792D01*
X264162Y-414250D01*
X262634Y-414833D01*
X260888Y-414250D01*
X259359Y-412500D01*
X258486Y-409875D01*
X258268Y-406958D01*
X258704Y-403167D01*
X259359Y-401124D01*
X260451Y-399083D01*
X261979Y-397625D01*
X263508Y-397333D01*
X265036Y-397916D01*
X266128Y-399375D01*
G01X275113Y-411333D02*
X276422Y-413375D01*
X278169Y-414541D01*
X280134Y-414833D01*
X281881Y-414541D01*
X283628Y-413083D01*
X284719Y-411333D01*
X284938Y-409583D01*
X284501Y-407542D01*
X282973Y-406083D01*
X281444Y-405500D01*
X279479D01*
G01X281444D02*
X282754Y-404625D01*
X283846Y-403167D01*
X284283Y-401417D01*
X283846Y-399666D01*
X282754Y-398208D01*
X280789Y-397333D01*
X278824Y-397625D01*
X276859Y-398792D01*
G01X293268Y-407542D02*
X294796Y-405500D01*
X296106Y-404333D01*
X297853Y-403750D01*
X299381Y-404333D01*
X300473Y-405500D01*
X301346Y-407250D01*
X301564Y-409291D01*
X301346Y-411042D01*
X300473Y-412792D01*
X299162Y-414250D01*
X297634Y-414833D01*
X295888Y-414250D01*
X294359Y-412500D01*
X293486Y-409875D01*
X293268Y-406958D01*
X293704Y-403167D01*
X294359Y-401124D01*
X295451Y-399083D01*
X296979Y-397625D01*
X298508Y-397333D01*
X300036Y-397916D01*
X301128Y-399375D01*
G01X311204Y-412792D02*
X312733Y-414250D01*
X314479Y-414833D01*
X316226Y-414250D01*
X317754Y-412500D01*
X318846Y-409875D01*
X319283Y-407250D01*
Y-404042D01*
X318846Y-401417D01*
X317754Y-399083D01*
X316444Y-397916D01*
X314916Y-397333D01*
X313169Y-397916D01*
X311859Y-399083D01*
X310986Y-400833D01*
X310549Y-403167D01*
X310986Y-405208D01*
X312078Y-407250D01*
X313388Y-408417D01*
X314916Y-408708D01*
X316662Y-408125D01*
X317973Y-406666D01*
X319283Y-404042D01*
G01X231799Y-369833D02*
Y-352333D01*
X237039D01*
X238786Y-353208D01*
X240096Y-355250D01*
X240533Y-357583D01*
X240096Y-359916D01*
X239004Y-361666D01*
X237039Y-362542D01*
X231799D01*
G01X258469Y-353792D02*
X257159Y-352916D01*
X255631Y-352333D01*
X253884D01*
X251919Y-353208D01*
X250391Y-354666D01*
X249299Y-356417D01*
X248426Y-359333D01*
X248207Y-361958D01*
X248644Y-364583D01*
X249299Y-366333D01*
X250609Y-368083D01*
X252138Y-369250D01*
X253666Y-369833D01*
X255194D01*
X256723Y-369250D01*
X258033Y-368375D01*
X259125Y-367209D01*
G01X272912Y-360500D02*
X273786Y-359625D01*
X274441Y-358167D01*
X274878Y-356124D01*
X274441Y-354375D01*
X273568Y-353208D01*
X272039Y-352333D01*
X266144D01*
Y-369833D01*
X273349D01*
X274878Y-368667D01*
X275751Y-366916D01*
X276188Y-364875D01*
X275751Y-362833D01*
X274441Y-361083D01*
X272912Y-360500D01*
X266144D01*
G01X282116Y-375666D02*
X295216D01*
G01X301144Y-369833D02*
Y-352333D01*
X311188Y-369833D01*
Y-352333D01*
G01X323666Y-369833D02*
X321919Y-369541D01*
X320391Y-368375D01*
X319081Y-366625D01*
X318207Y-364583D01*
X317771Y-362250D01*
Y-359916D01*
X318207Y-357583D01*
X319081Y-355541D01*
X320391Y-353792D01*
X321919Y-352625D01*
X323666Y-352333D01*
X325412Y-352625D01*
X326941Y-353792D01*
X328251Y-355541D01*
X329125Y-357583D01*
X329561Y-359916D01*
Y-362250D01*
X329125Y-364583D01*
X328251Y-366625D01*
X326941Y-368375D01*
X325412Y-369541D01*
X323666Y-369833D01*
G01X374507Y-352333D02*
X379966Y-369833D01*
X385425Y-352333D01*
G01X401833Y-369833D02*
X393099D01*
Y-352333D01*
X401833D01*
G01X398339Y-360791D02*
X393099D01*
G01X410599Y-369833D02*
Y-352333D01*
X416058D01*
X417804Y-353208D01*
X418896Y-354375D01*
X419333Y-356708D01*
X418896Y-359042D01*
X417586Y-360500D01*
X416058Y-361375D01*
X410599D01*
G01X416058D02*
X419333Y-369833D01*
G01X432466Y-370416D02*
X432029Y-370125D01*
Y-369541D01*
X432466Y-369250D01*
X432903Y-369541D01*
Y-370125D01*
X432466Y-370416D01*
G01X406216Y-414833D02*
Y-397333D01*
X403596Y-400833D01*
G01Y-414833D02*
X408836D01*
G01X580670Y-405500D02*
X579796Y-404625D01*
X579141Y-403167D01*
X578704Y-401124D01*
X579141Y-399375D01*
X580014Y-398208D01*
X581543Y-397333D01*
X587438D01*
Y-414833D01*
X580233D01*
X578704Y-413667D01*
X577831Y-411916D01*
X577394Y-409875D01*
X577831Y-407833D01*
X579141Y-406083D01*
X580670Y-405500D01*
X587438D01*
G01X569501Y-412500D02*
X567754Y-413958D01*
X565789Y-414833D01*
X564043D01*
X562296Y-413958D01*
X560986Y-412500D01*
X560331Y-410458D01*
X560768Y-408417D01*
X561859Y-406666D01*
X563824Y-405500D01*
X566444Y-404916D01*
X567973Y-403750D01*
X568628Y-401708D01*
X568191Y-399666D01*
X567099Y-398208D01*
X565571Y-397333D01*
X564043D01*
X562514Y-397916D01*
X561204Y-399375D01*
G01X550036Y-397333D02*
X544796D01*
G01X547416D02*
Y-414833D01*
G01X550036D02*
X544796D01*
G01X534283Y-397333D02*
Y-414833D01*
X525549D01*
G01X517219D02*
Y-397333D01*
G01X508923D02*
X517219Y-408125D01*
G01X507613Y-414833D02*
X513508Y-403167D01*
G01X508049Y-352333D02*
Y-369833D01*
X516783D01*
G01X533846D02*
Y-358167D01*
G01Y-360208D02*
X532973Y-359042D01*
X531662Y-358458D01*
X530134Y-358167D01*
X528606Y-358750D01*
X527296Y-359916D01*
X526422Y-361666D01*
X525986Y-364000D01*
X526422Y-366333D01*
X527296Y-368083D01*
X528606Y-369250D01*
X530134Y-369833D01*
X531662Y-369541D01*
X532973Y-368667D01*
X533846Y-367500D01*
G01X542831Y-375083D02*
X544141Y-375666D01*
X545888Y-375083D01*
X546979Y-373917D01*
X547853Y-372458D01*
X549162Y-367792D01*
X552001Y-358167D01*
G01X545014D02*
X549162Y-367792D01*
G01X561641Y-361958D02*
X568628D01*
X567973Y-359916D01*
X566881Y-358750D01*
X565353Y-358167D01*
X563824Y-358458D01*
X562514Y-359333D01*
X561641Y-361375D01*
X561204Y-363125D01*
Y-364875D01*
X561641Y-366625D01*
X562733Y-368375D01*
X564043Y-369541D01*
X565571Y-369833D01*
X567099Y-369250D01*
X568628Y-367500D01*
G01X579359Y-369833D02*
Y-358167D01*
G01Y-360500D02*
X580451Y-359333D01*
X581543Y-358458D01*
X583071Y-358167D01*
X584162Y-358458D01*
X585473Y-359333D01*
G01X672466Y-414833D02*
X670719Y-414541D01*
X669191Y-413375D01*
X667881Y-411625D01*
X667007Y-409583D01*
X666571Y-407250D01*
Y-404916D01*
X667007Y-402583D01*
X667881Y-400541D01*
X669191Y-398792D01*
X670719Y-397625D01*
X672466Y-397333D01*
X674212Y-397625D01*
X675741Y-398792D01*
X677051Y-400541D01*
X677925Y-402583D01*
X678361Y-404916D01*
Y-407250D01*
X677925Y-409583D01*
X677051Y-411625D01*
X675741Y-413375D01*
X674212Y-414541D01*
X672466Y-414833D01*
G01X674212Y-410166D02*
X676833Y-414833D01*
G01X685163Y-397333D02*
Y-409875D01*
X686036Y-412500D01*
X687783Y-414250D01*
X689966Y-414833D01*
X692149Y-414250D01*
X693896Y-412500D01*
X694769Y-409875D01*
Y-397333D01*
G01X704846D02*
X710086D01*
G01X707466D02*
Y-414833D01*
G01X704846D02*
X710086D01*
G01X719944D02*
Y-397333D01*
X729988Y-414833D01*
Y-397333D01*
G01X747269Y-398792D02*
X745959Y-397916D01*
X744431Y-397333D01*
X742684D01*
X740719Y-398208D01*
X739191Y-399666D01*
X738099Y-401417D01*
X737226Y-404333D01*
X737007Y-406958D01*
X737444Y-409583D01*
X738099Y-411333D01*
X739409Y-413083D01*
X740938Y-414250D01*
X742466Y-414833D01*
X743994D01*
X745523Y-414250D01*
X746833Y-413375D01*
X747925Y-412209D01*
G01X759966Y-414833D02*
Y-406958D01*
X755599Y-397333D01*
G01X764333D02*
X759966Y-406958D01*
G01X650163Y-369833D02*
Y-352333D01*
X654529D01*
X656276Y-353208D01*
X657586Y-354375D01*
X658678Y-356124D01*
X659551Y-358167D01*
X659769Y-361083D01*
X659551Y-364000D01*
X658678Y-366042D01*
X657586Y-367792D01*
X656276Y-368958D01*
X654529Y-369833D01*
X650163D01*
G01X669191Y-361958D02*
X676178D01*
X675523Y-359916D01*
X674431Y-358750D01*
X672903Y-358167D01*
X671374Y-358458D01*
X670064Y-359333D01*
X669191Y-361375D01*
X668754Y-363125D01*
Y-364875D01*
X669191Y-366625D01*
X670283Y-368375D01*
X671593Y-369541D01*
X673121Y-369833D01*
X674649Y-369250D01*
X676178Y-367500D01*
G01X686691Y-367792D02*
X687783Y-368958D01*
X689311Y-369833D01*
X690621D01*
X691931Y-369250D01*
X692804Y-368375D01*
X693241Y-367209D01*
X693023Y-365458D01*
X692149Y-364583D01*
X688219Y-362833D01*
X687346Y-360791D01*
X687783Y-359333D01*
X688656Y-358458D01*
X689966Y-358167D01*
X691276Y-358458D01*
X692586Y-359333D01*
G01X707466Y-358167D02*
Y-369833D01*
G01Y-353500D02*
X707029Y-353208D01*
Y-352625D01*
X707466Y-352333D01*
X707903Y-352625D01*
Y-353208D01*
X707466Y-353500D01*
G01X721909Y-374208D02*
X723438Y-375375D01*
X725184Y-375666D01*
X726712Y-375375D01*
X728023Y-373917D01*
X728896Y-371875D01*
Y-358167D01*
G01Y-360500D02*
X728023Y-359333D01*
X726712Y-358458D01*
X725184Y-358167D01*
X723438Y-358750D01*
X722346Y-359916D01*
X721472Y-361958D01*
X721036Y-364000D01*
X721254Y-365750D01*
X722128Y-367792D01*
X723438Y-369250D01*
X725184Y-369833D01*
X726494Y-369541D01*
X728023Y-368375D01*
X728896Y-367209D01*
G01X738754Y-369833D02*
Y-358167D01*
G01Y-361083D02*
X739628Y-359625D01*
X740938Y-358458D01*
X742684Y-358167D01*
X744212Y-358458D01*
X745523Y-359625D01*
X746178Y-361666D01*
Y-369833D01*
G01X756691Y-361958D02*
X763678D01*
X763023Y-359916D01*
X761931Y-358750D01*
X760403Y-358167D01*
X758874Y-358458D01*
X757564Y-359333D01*
X756691Y-361375D01*
X756254Y-363125D01*
Y-364875D01*
X756691Y-366625D01*
X757783Y-368375D01*
X759093Y-369541D01*
X760621Y-369833D01*
X762149Y-369250D01*
X763678Y-367500D01*
G01X774409Y-369833D02*
Y-358167D01*
G01Y-360500D02*
X775501Y-359333D01*
X776593Y-358458D01*
X778121Y-358167D01*
X779212Y-358458D01*
X780523Y-359333D01*
G01X821166Y-397333D02*
X819419Y-397916D01*
X818109Y-399375D01*
X817236Y-401124D01*
X816581Y-403458D01*
X816363Y-406083D01*
X816581Y-408708D01*
X817236Y-411042D01*
X818109Y-412792D01*
X819419Y-414250D01*
X821166Y-414833D01*
X822912Y-414250D01*
X824223Y-412792D01*
X825096Y-411042D01*
X825751Y-408708D01*
X825969Y-406083D01*
X825751Y-403458D01*
X825096Y-401124D01*
X824223Y-399375D01*
X822912Y-397916D01*
X821166Y-397333D01*
G01X834518Y-407542D02*
X836046Y-405500D01*
X837356Y-404333D01*
X839103Y-403750D01*
X840631Y-404333D01*
X841723Y-405500D01*
X842596Y-407250D01*
X842814Y-409291D01*
X842596Y-411042D01*
X841723Y-412792D01*
X840412Y-414250D01*
X838884Y-414833D01*
X837138Y-414250D01*
X835609Y-412500D01*
X834736Y-409875D01*
X834518Y-406958D01*
X834954Y-403167D01*
X835609Y-401124D01*
X836701Y-399083D01*
X838229Y-397625D01*
X839758Y-397333D01*
X841286Y-397916D01*
X842378Y-399375D01*
G01X852236Y-415416D02*
X860096Y-397333D01*
G01X873666D02*
X871919Y-397916D01*
X870609Y-399375D01*
X869736Y-401124D01*
X869081Y-403458D01*
X868863Y-406083D01*
X869081Y-408708D01*
X869736Y-411042D01*
X870609Y-412792D01*
X871919Y-414250D01*
X873666Y-414833D01*
X875412Y-414250D01*
X876723Y-412792D01*
X877596Y-411042D01*
X878251Y-408708D01*
X878469Y-406083D01*
X878251Y-403458D01*
X877596Y-401124D01*
X876723Y-399375D01*
X875412Y-397916D01*
X873666Y-397333D01*
G01X890729Y-414833D02*
X891166Y-411042D01*
X891821Y-407833D01*
X892694Y-404916D01*
X893786Y-401708D01*
X895533Y-397333D01*
X886799D01*
G01X904736Y-415416D02*
X912596Y-397333D01*
G01X922018Y-400250D02*
X923328Y-398500D01*
X924856Y-397625D01*
X926603Y-397333D01*
X928786Y-397916D01*
X930314Y-399375D01*
X930751Y-401124D01*
X930533Y-402875D01*
X929659Y-404333D01*
X925293Y-407250D01*
X923328Y-409291D01*
X922018Y-412209D01*
X921581Y-414833D01*
X930751D01*
G01X943666Y-397333D02*
X941919Y-397916D01*
X940609Y-399375D01*
X939736Y-401124D01*
X939081Y-403458D01*
X938863Y-406083D01*
X939081Y-408708D01*
X939736Y-411042D01*
X940609Y-412792D01*
X941919Y-414250D01*
X943666Y-414833D01*
X945412Y-414250D01*
X946723Y-412792D01*
X947596Y-411042D01*
X948251Y-408708D01*
X948469Y-406083D01*
X948251Y-403458D01*
X947596Y-401124D01*
X946723Y-399375D01*
X945412Y-397916D01*
X943666Y-397333D01*
G01X961166Y-414833D02*
Y-397333D01*
X958546Y-400833D01*
G01Y-414833D02*
X963786D01*
G01X978229D02*
X978666Y-411042D01*
X979321Y-407833D01*
X980194Y-404916D01*
X981286Y-401708D01*
X983033Y-397333D01*
X974299D01*
G01X868863Y-369833D02*
Y-352333D01*
X873229D01*
X874976Y-353208D01*
X876286Y-354375D01*
X877378Y-356124D01*
X878251Y-358167D01*
X878469Y-361083D01*
X878251Y-364000D01*
X877378Y-366042D01*
X876286Y-367792D01*
X874976Y-368958D01*
X873229Y-369833D01*
X868863D01*
G01X895096D02*
Y-358167D01*
G01Y-360208D02*
X894223Y-359042D01*
X892912Y-358458D01*
X891384Y-358167D01*
X889856Y-358750D01*
X888546Y-359916D01*
X887672Y-361666D01*
X887236Y-364000D01*
X887672Y-366333D01*
X888546Y-368083D01*
X889856Y-369250D01*
X891384Y-369833D01*
X892912Y-369541D01*
X894223Y-368667D01*
X895096Y-367500D01*
G01X908666Y-352333D02*
Y-369833D01*
G01X905609Y-358167D02*
X911723D01*
G01X922891Y-361958D02*
X929878D01*
X929223Y-359916D01*
X928131Y-358750D01*
X926603Y-358167D01*
X925074Y-358458D01*
X923764Y-359333D01*
X922891Y-361375D01*
X922454Y-363125D01*
Y-364875D01*
X922891Y-366625D01*
X923983Y-368375D01*
X925293Y-369541D01*
X926821Y-369833D01*
X928349Y-369250D01*
X929878Y-367500D01*
G01X8122Y71978D02*
X15122D01*
X9289Y75445D01*
X15122Y78912D01*
X8122D01*
G01Y80712D02*
X15122Y84045D01*
X8122Y87378D01*
G01X10572Y86178D02*
Y81912D01*
G01X8122Y89712D02*
X15122D01*
Y92378D01*
X14772Y93445D01*
X14305Y94245D01*
X13605Y94912D01*
X12789Y95445D01*
X11622Y95578D01*
X10455Y95445D01*
X9639Y94912D01*
X8938Y94245D01*
X8472Y93445D01*
X8122Y92378D01*
Y89712D01*
G01Y103912D02*
Y98578D01*
X15122D01*
Y103912D01*
G01X11739Y101778D02*
Y98578D01*
G01X15122Y116845D02*
Y120045D01*
G01Y118445D02*
X8122D01*
G01Y116845D02*
Y120045D01*
G01Y123978D02*
X15122D01*
X8122Y130112D01*
X15122D01*
G01Y144245D02*
X8122D01*
G01X15122Y141178D02*
Y147312D01*
G01X8122Y149512D02*
X15122Y152845D01*
X8122Y156178D01*
G01X10572Y154978D02*
Y150712D01*
G01X15122Y159845D02*
Y163045D01*
G01Y161445D02*
X8122D01*
G01Y159845D02*
Y163045D01*
G01X15122Y166045D02*
X8122Y167912D01*
X15122Y170045D01*
X8122Y172178D01*
X15122Y174045D01*
G01X8122Y175312D02*
X15122Y178645D01*
X8122Y181978D01*
G01X10572Y180778D02*
Y176512D01*
G01X8122Y184178D02*
X15122D01*
X8122Y190312D01*
X15122D01*
G01X196200Y70200D02*
X203200D01*
X201800Y68600D01*
G01X196200D02*
Y71800D01*
G01X199116Y76267D02*
X199933Y77200D01*
X200400Y78000D01*
X200633Y79067D01*
X200400Y80000D01*
X199933Y80667D01*
X199233Y81200D01*
X198417Y81333D01*
X197717Y81200D01*
X197016Y80667D01*
X196433Y79867D01*
X196200Y78933D01*
X196433Y77867D01*
X197133Y76933D01*
X198183Y76400D01*
X199350Y76267D01*
X200867Y76533D01*
X201683Y76933D01*
X202500Y77600D01*
X203083Y78533D01*
X203200Y79467D01*
X202967Y80400D01*
X202383Y81067D01*
G01X197600Y84467D02*
X196783Y85267D01*
X196317Y86333D01*
X196200Y87533D01*
X196317Y88600D01*
X196900Y89667D01*
X197600Y90333D01*
X198300Y90467D01*
X199116Y90200D01*
X199700Y89267D01*
X199933Y88333D01*
Y87133D01*
G01Y88333D02*
X200283Y89133D01*
X200867Y89800D01*
X201567Y90067D01*
X202267Y89800D01*
X202850Y89133D01*
X203200Y87933D01*
X203083Y86733D01*
X202617Y85533D01*
G01X199116Y93467D02*
X199933Y94400D01*
X200400Y95200D01*
X200633Y96267D01*
X200400Y97200D01*
X199933Y97867D01*
X199233Y98400D01*
X198417Y98533D01*
X197717Y98400D01*
X197016Y97867D01*
X196433Y97067D01*
X196200Y96133D01*
X196433Y95067D01*
X197133Y94133D01*
X198183Y93600D01*
X199350Y93467D01*
X200867Y93733D01*
X201683Y94133D01*
X202500Y94800D01*
X203083Y95733D01*
X203200Y96667D01*
X202967Y97600D01*
X202383Y98267D01*
G01X197016Y102333D02*
X196433Y103267D01*
X196200Y104333D01*
X196433Y105400D01*
X197133Y106333D01*
X198183Y107000D01*
X199233Y107267D01*
X200517D01*
X201567Y107000D01*
X202500Y106333D01*
X202967Y105533D01*
X203200Y104600D01*
X202967Y103533D01*
X202500Y102733D01*
X201800Y102200D01*
X200867Y101933D01*
X200050Y102200D01*
X199233Y102867D01*
X198767Y103667D01*
X198650Y104600D01*
X198883Y105667D01*
X199467Y106467D01*
X200517Y107267D01*
G01X198533Y111467D02*
Y114933D01*
G01X196200Y121800D02*
X203200D01*
X201800Y120200D01*
G01X196200D02*
Y123400D01*
G01X216733Y22267D02*
X217083Y22800D01*
X217667Y23200D01*
X218483Y23467D01*
X219183Y23200D01*
X219650Y22667D01*
X220000Y21733D01*
Y18133D01*
X213000D01*
Y22533D01*
X213467Y23467D01*
X214167Y24000D01*
X214983Y24267D01*
X215800Y24000D01*
X216500Y23200D01*
X216733Y22267D01*
Y18133D01*
G01X213000Y27933D02*
X217667D01*
G01X216733D02*
X217200Y28600D01*
X217550Y29267D01*
X217667Y30200D01*
X217550Y30867D01*
X217200Y31667D01*
G01X210900Y35600D02*
X210667Y36400D01*
X210900Y37467D01*
X211367Y38133D01*
X211950Y38667D01*
X213816Y39467D01*
X217667Y41200D01*
G01Y36933D02*
X213816Y39467D01*
G01X217083Y49133D02*
X217550Y48200D01*
X217667Y47400D01*
X217433Y46333D01*
X216967Y45533D01*
X216150Y45000D01*
X215333Y44867D01*
X214517Y45000D01*
X213816Y45533D01*
X213233Y46333D01*
X213000Y47400D01*
X213233Y48333D01*
X213700Y49133D01*
G01X216150Y53600D02*
Y57867D01*
X216967Y57467D01*
X217433Y56800D01*
X217667Y55867D01*
X217550Y54933D01*
X217200Y54133D01*
X216383Y53600D01*
X215683Y53333D01*
X214983D01*
X214283Y53600D01*
X213583Y54267D01*
X213117Y55067D01*
X213000Y56000D01*
X213233Y56933D01*
X213933Y57867D01*
G01X219417Y75733D02*
X219767Y74933D01*
X220000Y74000D01*
Y72933D01*
X219650Y71733D01*
X219067Y70800D01*
X218367Y70133D01*
X217200Y69600D01*
X216150Y69467D01*
X215100Y69733D01*
X214400Y70133D01*
X213700Y70933D01*
X213233Y71867D01*
X213000Y72800D01*
Y73733D01*
X213233Y74667D01*
X213583Y75467D01*
X214050Y76133D01*
G01X213000Y83800D02*
X217667D01*
G01X216850D02*
X217317Y83267D01*
X217550Y82467D01*
X217667Y81533D01*
X217433Y80600D01*
X216967Y79800D01*
X216267Y79267D01*
X215333Y79000D01*
X214400Y79267D01*
X213700Y79800D01*
X213233Y80600D01*
X213000Y81533D01*
X213117Y82467D01*
X213467Y83267D01*
X213933Y83800D01*
G01X213000Y87733D02*
X217667D01*
G01X216500D02*
X217083Y88267D01*
X217550Y89067D01*
X217667Y90133D01*
X217550Y91067D01*
X217083Y91867D01*
X216267Y92267D01*
X213000D01*
G01X210900Y95800D02*
X210667Y96600D01*
X210900Y97667D01*
X211367Y98333D01*
X211950Y98867D01*
X213816Y99667D01*
X217667Y101400D01*
G01Y97133D02*
X213816Y99667D01*
G01X213000Y107200D02*
X213117Y106400D01*
X213583Y105600D01*
X214400Y105067D01*
X215333Y104800D01*
X216267Y105067D01*
X217083Y105600D01*
X217550Y106400D01*
X217667Y107200D01*
X217550Y108000D01*
X217083Y108800D01*
X216267Y109333D01*
X215333Y109467D01*
X214400Y109333D01*
X213583Y108800D01*
X213117Y108000D01*
X213000Y107200D01*
G01Y113533D02*
X217667D01*
G01X216500D02*
X217083Y114067D01*
X217550Y114867D01*
X217667Y115933D01*
X217550Y116867D01*
X217083Y117667D01*
X216267Y118067D01*
X213000D01*
G01Y130467D02*
X220000D01*
Y135533D01*
G01X216617Y133667D02*
Y130467D01*
G01X213000Y139733D02*
X217667D01*
G01X216733D02*
X217200Y140400D01*
X217550Y141067D01*
X217667Y142000D01*
X217550Y142667D01*
X217200Y143467D01*
G01X213000Y150200D02*
X213117Y149400D01*
X213583Y148600D01*
X214400Y148067D01*
X215333Y147800D01*
X216267Y148067D01*
X217083Y148600D01*
X217550Y149400D01*
X217667Y150200D01*
X217550Y151000D01*
X217083Y151800D01*
X216267Y152333D01*
X215333Y152467D01*
X214400Y152333D01*
X213583Y151800D01*
X213117Y151000D01*
X213000Y150200D01*
G01Y156533D02*
X217667D01*
G01X216500D02*
X217083Y157067D01*
X217550Y157867D01*
X217667Y158933D01*
X217550Y159867D01*
X217083Y160667D01*
X216267Y161067D01*
X213000D01*
G01X220000Y167400D02*
X213000D01*
G01X217667Y165533D02*
Y169267D01*
G01X213000Y181933D02*
X220000D01*
Y185133D01*
X219650Y186200D01*
X218833Y187000D01*
X217900Y187267D01*
X216967Y187000D01*
X216267Y186333D01*
X215916Y185133D01*
Y181933D01*
G01X213000Y195600D02*
X217667D01*
G01X216850D02*
X217317Y195067D01*
X217550Y194267D01*
X217667Y193333D01*
X217433Y192400D01*
X216967Y191600D01*
X216267Y191067D01*
X215333Y190800D01*
X214400Y191067D01*
X213700Y191600D01*
X213233Y192400D01*
X213000Y193333D01*
X213117Y194267D01*
X213467Y195067D01*
X213933Y195600D01*
G01X213000Y199533D02*
X217667D01*
G01X216500D02*
X217083Y200067D01*
X217550Y200867D01*
X217667Y201933D01*
X217550Y202867D01*
X217083Y203667D01*
X216267Y204067D01*
X213000D01*
G01X216150Y208400D02*
Y212667D01*
X216967Y212267D01*
X217433Y211600D01*
X217667Y210667D01*
X217550Y209733D01*
X217200Y208933D01*
X216383Y208400D01*
X215683Y208133D01*
X214983D01*
X214283Y208400D01*
X213583Y209067D01*
X213117Y209867D01*
X213000Y210800D01*
X213233Y211733D01*
X213933Y212667D01*
G01X213000Y219000D02*
X220000D01*
G01X216733Y237267D02*
X217083Y237800D01*
X217667Y238200D01*
X218483Y238467D01*
X219183Y238200D01*
X219650Y237667D01*
X220000Y236733D01*
Y233133D01*
X213000D01*
Y237533D01*
X213467Y238467D01*
X214167Y239000D01*
X214983Y239267D01*
X215800Y239000D01*
X216500Y238200D01*
X216733Y237267D01*
Y233133D01*
G01X213000Y244800D02*
X213117Y244000D01*
X213583Y243200D01*
X214400Y242667D01*
X215333Y242400D01*
X216267Y242667D01*
X217083Y243200D01*
X217550Y244000D01*
X217667Y244800D01*
X217550Y245600D01*
X217083Y246400D01*
X216267Y246933D01*
X215333Y247067D01*
X214400Y246933D01*
X213583Y246400D01*
X213117Y245600D01*
X213000Y244800D01*
G01Y255800D02*
X217667D01*
G01X216850D02*
X217317Y255267D01*
X217550Y254467D01*
X217667Y253533D01*
X217433Y252600D01*
X216967Y251800D01*
X216267Y251267D01*
X215333Y251000D01*
X214400Y251267D01*
X213700Y251800D01*
X213233Y252600D01*
X213000Y253533D01*
X213117Y254467D01*
X213467Y255267D01*
X213933Y255800D01*
G01X213000Y260133D02*
X217667D01*
G01X216733D02*
X217200Y260800D01*
X217550Y261467D01*
X217667Y262400D01*
X217550Y263067D01*
X217200Y263867D01*
G01X220000Y273000D02*
X213000D01*
G01X214050D02*
X213467Y272467D01*
X213117Y271667D01*
X213000Y270733D01*
X213233Y269667D01*
X213816Y268867D01*
X214517Y268333D01*
X215333Y268200D01*
X216150Y268333D01*
X216850Y268867D01*
X217433Y269667D01*
X217667Y270733D01*
X217550Y271667D01*
X217317Y272333D01*
X216850Y273000D01*
G01X182423Y25377D02*
X182773Y25910D01*
X183357Y26310D01*
X184173Y26577D01*
X184873Y26310D01*
X185340Y25777D01*
X185690Y24843D01*
Y21243D01*
X178690D01*
Y25643D01*
X179157Y26577D01*
X179857Y27110D01*
X180673Y27377D01*
X181490Y27110D01*
X182190Y26310D01*
X182423Y25377D01*
Y21243D01*
G01X178690Y34510D02*
X185690D01*
X180673Y29577D01*
Y36243D01*
G01X178690Y41510D02*
X178807Y42443D01*
X179157Y43510D01*
X179740Y44177D01*
X180557Y44443D01*
X181373Y44177D01*
X182073Y43377D01*
X182423Y42177D01*
Y40843D01*
X182657Y40043D01*
X183240Y39377D01*
X184057Y39110D01*
X184873Y39510D01*
X185457Y40443D01*
X185690Y41510D01*
X185457Y42577D01*
X184873Y43510D01*
X184057Y43910D01*
X183240Y43643D01*
X182657Y42977D01*
X182423Y42177D01*
Y40843D01*
X182073Y39643D01*
X181373Y38843D01*
X180557Y38577D01*
X179740Y38843D01*
X179157Y39510D01*
X178807Y40577D01*
X178690Y41510D01*
G01X178457Y50110D02*
X178573Y49843D01*
X178807D01*
X178923Y50110D01*
X178807Y50377D01*
X178573D01*
X178457Y50110D01*
G01X185690Y58710D02*
X185457Y57643D01*
X184873Y56843D01*
X184173Y56310D01*
X183240Y55910D01*
X182190Y55777D01*
X181140Y55910D01*
X180207Y56310D01*
X179506Y56843D01*
X178923Y57643D01*
X178690Y58710D01*
X178923Y59777D01*
X179506Y60577D01*
X180207Y61110D01*
X181140Y61510D01*
X182190Y61643D01*
X183240Y61510D01*
X184173Y61110D01*
X184873Y60577D01*
X185457Y59777D01*
X185690Y58710D01*
G01X178690Y67310D02*
X185690D01*
X184290Y65710D01*
G01X178690D02*
Y68910D01*
G01Y75910D02*
X185690D01*
X184290Y74310D01*
G01X178690D02*
Y77510D01*
G01X184523Y81977D02*
X185223Y82777D01*
X185573Y83710D01*
X185690Y84777D01*
X185457Y86110D01*
X184873Y87043D01*
X184173Y87310D01*
X183473Y87177D01*
X182890Y86643D01*
X181723Y83977D01*
X180907Y82777D01*
X179740Y81977D01*
X178690Y81710D01*
Y87310D01*
G01X185690Y93110D02*
X185457Y92043D01*
X184873Y91243D01*
X184173Y90710D01*
X183240Y90310D01*
X182190Y90177D01*
X181140Y90310D01*
X180207Y90710D01*
X179506Y91243D01*
X178923Y92043D01*
X178690Y93110D01*
X178923Y94177D01*
X179506Y94977D01*
X180207Y95510D01*
X181140Y95910D01*
X182190Y96043D01*
X183240Y95910D01*
X184173Y95510D01*
X184873Y94977D01*
X185457Y94177D01*
X185690Y93110D01*
G01X178457Y101710D02*
X178573Y101443D01*
X178807D01*
X178923Y101710D01*
X178807Y101977D01*
X178573D01*
X178457Y101710D01*
G01X185690Y110310D02*
X185457Y109243D01*
X184873Y108443D01*
X184173Y107910D01*
X183240Y107510D01*
X182190Y107377D01*
X181140Y107510D01*
X180207Y107910D01*
X179506Y108443D01*
X178923Y109243D01*
X178690Y110310D01*
X178923Y111377D01*
X179506Y112177D01*
X180207Y112710D01*
X181140Y113110D01*
X182190Y113243D01*
X183240Y113110D01*
X184173Y112710D01*
X184873Y112177D01*
X185457Y111377D01*
X185690Y110310D01*
G01Y118910D02*
X185457Y117843D01*
X184873Y117043D01*
X184173Y116510D01*
X183240Y116110D01*
X182190Y115977D01*
X181140Y116110D01*
X180207Y116510D01*
X179506Y117043D01*
X178923Y117843D01*
X178690Y118910D01*
X178923Y119977D01*
X179506Y120777D01*
X180207Y121310D01*
X181140Y121710D01*
X182190Y121843D01*
X183240Y121710D01*
X184173Y121310D01*
X184873Y120777D01*
X185457Y119977D01*
X185690Y118910D01*
G01X178690Y127510D02*
X185690D01*
X184290Y125910D01*
G01X178690D02*
Y129110D01*
G01Y136110D02*
X185690D01*
X184290Y134510D01*
G01X178690D02*
Y137710D01*
M02*
